5
5
4
4
3
3
2
2
1
1
D D
C C
B B
A A
Bryce Canyon 
PCB P/N:   16318
Version:     2
Layer:         8 Layers   
IO Module_Broadcom IOC
Title 
Size Document Number Rev
Date: Sheet 
of 
Bryce Canyon_IO Module 2
COVER PAGE 
A3 
1 47 Friday, December 08, 2017 
Bryce Canyon_IO Module 
http://www.wiwynn.com 
8F, 90, Sec.1, Xintai 5th Rd., Xizhi Dist.,
New Taipei City 22102, Taiwan (R.O.C.)
Title 
Size Document Number Rev
Date: Sheet 
of 
Bryce Canyon_IO Module 2
COVER PAGE 
A3 
1 47 Friday, December 08, 2017 
Bryce Canyon_IO Module 
http://www.wiwynn.com 
8F, 90, Sec.1, Xintai 5th Rd., Xizhi Dist.,
New Taipei City 22102, Taiwan (R.O.C.)
Title 
Size Document Number Rev
Date: Sheet 
of 
Bryce Canyon_IO Module 2
COVER PAGE 
A3 
1 47 Friday, December 08, 2017 
Bryce Canyon_IO Module 
http://www.wiwynn.com 
8F, 90, Sec.1, Xintai 5th Rd., Xizhi Dist.,
New Taipei City 22102, Taiwan (R.O.C.)



5
5
4
4
3
3
2
2
1
1
D D
C C
B B
A A
TABLE OF CONTENTS
UART TOPOLOGY
30
STACK-UPTABLE OF CONTENTSBLOCK DIAGRAMPOWER SEQUENCEI2C TOPOLOGYPOWER FLOW
12 16 17 21 2213 14 15 2918 19 2004 05 23 24 27 28111002 03 06 0908 25 2607
COVER PAGE
01
PAGE TITLE
PAGE TITLE PAGE
PAGE
PAGE PAGE TITLE
31 32 33 34 35 36 37 38 39 40
41 42 43 44
CLOCK TREEPOWER DISTRIBUTION HOT SWAP CONTROLLER ADM1278XCEDE CONNECTOROCP2.0_MEZZ CONN_AOCP2.0_MEZZ CONN_B & CUSB2.0 x1TPMPOWER & RESET BUTTON DEBUG PORTRESERVEI2C SWITCH & BUFFERIOM I2C DEVICEAST2500 I2C DDR LPCAST2500 UART LAN SPIAST2500 FAN ADCAST2500 POWERAST2500 STRAP PINAST2500 VOLTAGE SENSEPWRSW_P5V_STBY_TPS53318PWRSW_P3V3_STBY_TPS53318PWRLDO_P2V5_STBY_TPS74801PWRSW_P1V8_STBY_TPS53312PWRLDO_P1V2_STBY_TPS74801PWRLDO_P1V5_STBY_TPS74801PWRSW_P0V975_STBY_VT235WFQXSAS3008_PCIE & VIA
SAS3008_EXT_MINI SAS CONN*2SAS3008_POWER&GNDSAS3008_I2C&UART LEVELSHIFTSAS3008_POWER_2
PWRLDO_P1V15_STBY_TPS74801
45
SAS3008_GPIO & USB & ETHSAS3008_MISCSAS3008_FLASHSAS3008_SAS & VIA
SAS3008_POWER_1
46
SCREW HOLE
47
SAS3008_SAS CONN LED
Title 
Size Document Number Rev
Date: Sheet 
of 
Bryce Canyon_IO Module 2
TABLE OF CONTENTS 
A3 
2 47 Friday, December 08, 2017 
Bryce Canyon_IO Module 
http://www.wiwynn.com 
8F, 90, Sec.1, Xintai 5th Rd., Xizhi Dist.,
New Taipei City 22102, Taiwan (R.O.C.)
Title 
Size Document Number Rev
Date: Sheet 
of 
Bryce Canyon_IO Module 2
TABLE OF CONTENTS 
A3 
2 47 Friday, December 08, 2017 
Bryce Canyon_IO Module 
http://www.wiwynn.com 
8F, 90, Sec.1, Xintai 5th Rd., Xizhi Dist.,
New Taipei City 22102, Taiwan (R.O.C.)
Title 
Size Document Number Rev
Date: Sheet 
of 
Bryce Canyon_IO Module 2
TABLE OF CONTENTS 
A3 
2 47 Friday, December 08, 2017 
Bryce Canyon_IO Module 
http://www.wiwynn.com 
8F, 90, Sec.1, Xintai 5th Rd., Xizhi Dist.,
New Taipei City 22102, Taiwan (R.O.C.)



5
5
4
4
3
3
2
2
1
1
D D
C C
B B
A A
BLOCK DIAGRAM
   BMC 
(AST2500) 
MONO LAKE 
PCIe x8 
IOC 
       EXT 
MINI SAS HD CONN_A 
       EXT 
MINI SAS HD CONN_B 
SAS x4 SAS x4 
I2C 
Mezzanine Card 
  (OCP 2.0) 
I2C PCIe x8 
I2C*2 
NCSI 
I2C*2 I2C I2C 
R.DPB 
I2C*2 
EXP IOC 
SCC Board(A/B) 
USB Hub 
USB 2.0 
  USB3.0 
Connector 
USB 2.0 
SWITCH 
BMC_UART 
CPU_UART 
UART 
PWR & RST 
   BTN 
GPI 
PWR BTN 
 (GPO) 
RST BTN 
 (GPO) 
BMC 
SPI 
SPI 
USB 2.0 
NOR Flash 
CONN LED 
   x2 
GPO F.DPB 
BMC 
SPI 
I2C TPM 
I2C 
Title 
Size Document Number Rev
Date: Sheet 
of 
Bryce Canyon_IO Module 2
BLOCK DIAGRAM 
A3 
3 47Friday, December 08, 2017 
Bryce Canyon_IO Module 
http://www.wiwynn.com 
8F, 90, Sec.1, Xintai 5th Rd., Xizhi Dist.,
New Taipei City 22102, Taiwan (R.O.C.)
Title 
Size Document Number Rev
Date: Sheet 
of 
Bryce Canyon_IO Module 2
BLOCK DIAGRAM 
A3 
3 47Friday, December 08, 2017 
Bryce Canyon_IO Module 
http://www.wiwynn.com 
8F, 90, Sec.1, Xintai 5th Rd., Xizhi Dist.,
New Taipei City 22102, Taiwan (R.O.C.)
Title 
Size Document Number Rev
Date: Sheet 
of 
Bryce Canyon_IO Module 2
BLOCK DIAGRAM 
A3 
3 47Friday, December 08, 2017 
Bryce Canyon_IO Module 
http://www.wiwynn.com 
8F, 90, Sec.1, Xintai 5th Rd., Xizhi Dist.,
New Taipei City 22102, Taiwan (R.O.C.)



5
5
4
4
3
3
2
2
1
1
D D
C C
B B
A A
POWER DISTRIBUTION
P12V 2.4A
P1V5   0.36A
P1V8   0.66A
3.3V   3A
P3V3_SBTY
1.8V   2.178A
P1V8_STBY
VR LINEAR
    (LDO)
USB2
P5V_STBY   0.5AP5V_STBY
P0V975
BMC AST2500
P1V15_STBY  663mA
P3V3_STBY   200mA
P1V2_STBY   495mA
~15W
0.975V   14.37A
P0V975_STBY
VR SWITCHING
P5V_STBY
5V  3.4A
P5V_STBY  2.4A
P3V3_STBY  1.6AP3V3_STBY
P1V8
25/50G Mezzanine Card 
P12V
SAS LSI 3008
P5V_STBY
P1V2_STBY
P1V15_STBY
P1V2_STBY 
1.2V 495mA 
P1V15_STBY 
1.15V 663mA 
P12V
0.33A 
P1V5P1V5 
1.5V 360mA 
1.17A 
0.825A Debug Card
P5V_STBY   0.5AP5V_STBY
1.42A 
2.4A 
6.15A 
~46W
~2W
~2.5W
~2.5W
P3V3_STBY
PCE_AVDD       1.743A
SAS0_AVDD       2.843A
P0V975       9.782A
P0V975
P0V975
Others(Logic circuit)
P3V3_STBY  1AP3V3_STBY ~3.3W
P2V5_STBY   200mAP2V5_STBY 
2.5V 200mA 
P2V5_STBY
Title 
Size Document Number Rev
Date: Sheet 
of 
Bryce Canyon_IO Module 2
POWER DISTRIBUTION 
A3 
4 47Friday, December 08, 2017 
Bryce Canyon_IO Module 
http://www.wiwynn.com 
8F, 90, Sec.1, Xintai 5th Rd., Xizhi Dist.,
New Taipei City 22102, Taiwan (R.O.C.)
Title 
Size Document Number Rev
Date: Sheet 
of 
Bryce Canyon_IO Module 2
POWER DISTRIBUTION 
A3 
4 47Friday, December 08, 2017 
Bryce Canyon_IO Module 
http://www.wiwynn.com 
8F, 90, Sec.1, Xintai 5th Rd., Xizhi Dist.,
New Taipei City 22102, Taiwan (R.O.C.)
Title 
Size Document Number Rev
Date: Sheet 
of 
Bryce Canyon_IO Module 2
POWER DISTRIBUTION 
A3 
4 47Friday, December 08, 2017 
Bryce Canyon_IO Module 
http://www.wiwynn.com 
8F, 90, Sec.1, Xintai 5th Rd., Xizhi Dist.,
New Taipei City 22102, Taiwan (R.O.C.)



5
5
4
4
3
3
2
2
1
1
D D
C C
B B
A A
POWER FLOW
EN:0~7V 
P12V_STBY 
Switching 
Soft Start Time: 2.8ms 
SUPPLY CURRENT: 3.4A 
OCP: 4.5A 
P5V_STBY_VREG(5V) 
P5V_STBY 
(OD) 
OUT 
PGOOD 
IN 
EN 
PWRGD_P5V_STBY TPS53318DQPR-GP IOM_PGOOD_OUT 
10K Ω
15K Ω
EN:0~7V 
Switching 
Soft Start Time: 5.6ms 
SUPPLY CURRENT: 3.562A 
OCP : 4.6A 
(OD) 
OUT 
PGOOD 
IN 
EN 
TPS53318DQPR-GP 
P3V3_STBY P12V_STBY 
P3V3_STBY_VREG(5V) 
10k Ω
15k Ω
EN:0~18V 
Switching 
Soft Start Time: 1.4ms 
SUPPLY CURRENT: 2.178A 
OCP:4.1A 
(OD) 
OUT 
PGOOD 
IN 
EN 
TPS53312RGTR-GP 
P1V8_STBY P12V_STBY 
10k Ω
P3V3_STBY 
EN:0~6V 
LDO 
Soft Start Time: 0.86ms 
SUPPLY CURRENT: 0.495A 
OCP:2A 
(OD) 
OUT 
PGOOD 
IN 
EN 
TPS74801RGW-GP 
P1V2_STBY P1V8_STBY 
10k Ω
P3V3_STBY 
PWRGD_P3V3_STBY 
PWRGD_P1V8_STBY 
PWRGD_P1V2_STBY 
EN:0~6V 
LDO 
Soft Start Time: 0.86ms 
SUPPLY CURRENT: 0.663A 
OCP:2A 
(OD) 
OUT 
PGOOD 
IN 
EN 
TPS74801RGW-GP 
P1V12_STBY P1V8_STBY 
10k Ω
P3V3_STBY 
PWRGD_P1V15_STBY 
Hot Swap Controller 
SUPPLY CURRENT: 6.1A 
OCP: 9.12A 
(OD) 
OUT 
PGOOD 
IN 
EN 
ADM1278 
P12V_IOM P12V_STBY 
10K Ω
3.83K Ω
P12V_STBY 
P12V_A_PGOOD 
EN:0~5V 
SWITCH 
SUPPLY CURRENT: 14.37A 
OCP:20A 
(OD) 
OUT 
PGOOD 
IN 
EN 
TPS74801RGW-GP 
P0V975 P12V_STBY 
PG_STAT_P0V975 
4.7kΩ
P3V3_STBY 
EN:0~6V 
LDO 
Soft Start Time: 0.86ms 
SUPPLY CURRENT: 0.2A 
OCP:2A 
(OD) 
OUT 
PGOOD 
IN 
EN 
TPS74801RGW-GP 
P2V5_STBY P3V3_STBY 
10k Ω
P3V3_STBY 
PWRGD_P2V5_STBY 
P1V8 P1V8_STBY 
4.02K Ω
P3V3_STBY P12V 
20K Ω
P3V3 P3V3_STBY 
2.2K Ω
P3V3_STBY P12V 
10K Ω
AND 
Gate 
EN:0~6V 
LDO 
Soft Start Time: 0.86ms 
SUPPLY CURRENT: 0.36A 
OCP:2A 
(OD) 
OUT 
PGOOD 
IN 
EN 
TPS74801RGW-GP 
P1V5 P1V8_STBY 
10k Ω
PWRGD_P1V5_STBY 
P3V3_STBY 
IOM_FULL_PWR_EN 
PWRGD_P3V3 
P3V3_STBY 
4.7K Ω
P3V3 
4.7K Ω
4.7K Ω
P3V3 
PWRGD_P1V8 
P3V3_STBY 
4.7K Ω
P3V3_STBY 
4.7K Ω
4.7K Ω
P1V8 
IOC 
Title 
Size Document Number Rev
Date: Sheet 
of 
Bryce Canyon_IO Module 2
POWER FLOW 
A2 
5 47 Friday, December 08, 2017 
Bryce Canyon_IO Module 
http://www.wiwynn.com 
8F, 90, Sec.1, Xintai 5th Rd., Xizhi Dist.,
New Taipei City 22102, Taiwan (R.O.C.)
Title 
Size Document Number Rev
Date: Sheet 
of 
Bryce Canyon_IO Module 2
POWER FLOW 
A2 
5 47 Friday, December 08, 2017 
Bryce Canyon_IO Module 
http://www.wiwynn.com 
8F, 90, Sec.1, Xintai 5th Rd., Xizhi Dist.,
New Taipei City 22102, Taiwan (R.O.C.)
Title 
Size Document Number Rev
Date: Sheet 
of 
Bryce Canyon_IO Module 2
POWER FLOW 
A2 
5 47 Friday, December 08, 2017 
Bryce Canyon_IO Module 
http://www.wiwynn.com 
8F, 90, Sec.1, Xintai 5th Rd., Xizhi Dist.,
New Taipei City 22102, Taiwan (R.O.C.)



5
5
4
4
3
3
2
2
1
1
D D
C C
B B
A A
POWER SEQUENCE
SOURCE DESTINATION SIG/PWR 
F./R.DPB(P12V_IOM) IO MODULE P12V_STBY 
P12V_STBY P5V_STBY USB, DEBUG CARD, 25/50G 
Soft Start: 2.8ms 
P12V_STBY P3V3_STBY BMC, 25/50G, others 
Soft Start: 5.6ms 
P3V3_STBY BMC P2V5_STBY Soft Start: 1.4ms 
Soft Start: 0.86ms 
Soft Start: 0.86ms 
P12V_STBY BMC P1V8_STBY 
P1V8_STBY BMC P1V2_STBY 
P1V8_STBY IOC P1V8 
P12V_STBY IOC P0V975 
BMC F.DPB COMP_PWR_EN 
MONO LAKE IOC, 25/50G PCIE_RST_N 
Soft Start: 1.4ms 
P1V15_STBY BMC P1V8_STBY 
P3V3 
IOC P1V5 
25/50G, others 
P1V8_STBY 
Soft Start: 0.86ms 
BMC(FULL POWER ENABLE) 
IOM_STBY_PGOOD BMC FM_BMC_RESET_N 
IOM_FULL_PGOOD BMC P0V975_PWRGOOD 
Title 
Size Document Number Rev
Date: Sheet 
of 
Bryce Canyon_IO Module 2
POWER SEQUENCE 
A3 
6 47 Friday, December 08, 2017 
Bryce Canyon_IO Module 
http://www.wiwynn.com 
8F, 90, Sec.1, Xintai 5th Rd., Xizhi Dist.,
New Taipei City 22102, Taiwan (R.O.C.)
Title 
Size Document Number Rev
Date: Sheet 
of 
Bryce Canyon_IO Module 2
POWER SEQUENCE 
A3 
6 47 Friday, December 08, 2017 
Bryce Canyon_IO Module 
http://www.wiwynn.com 
8F, 90, Sec.1, Xintai 5th Rd., Xizhi Dist.,
New Taipei City 22102, Taiwan (R.O.C.)
Title 
Size Document Number Rev
Date: Sheet 
of 
Bryce Canyon_IO Module 2
POWER SEQUENCE 
A3 
6 47 Friday, December 08, 2017 
Bryce Canyon_IO Module 
http://www.wiwynn.com 
8F, 90, Sec.1, Xintai 5th Rd., Xizhi Dist.,
New Taipei City 22102, Taiwan (R.O.C.)



5
5
4
4
3
3
2
2
1
1
D D
C C
B B
A A
ClOCK TREE
MEZZANINE CARD(25/50G)
PCIE4_REFCLK 100MHz_MEZZ(Primary)
CLOCK 
BUFFER 
Mono Lake 
BMC AST2500
50MHzOSC
MAC1 
NCSI 
PCIE2_REFCLK
XTAL25MHz
IOC SAS3008
100MHz_SAS3008
PCIe Clock
SAS Clock
24MHz
OSCClock
XTAL24MHz
USB Hub
Clock
Title 
Size Document Number Rev
Date: Sheet 
of 
Bryce Canyon_IO Module 2
CLOCK TREE 
A3 
7 47Friday, December 08, 2017 
Bryce Canyon_IO Module 
http://www.wiwynn.com 
8F, 90, Sec.1, Xintai 5th Rd., Xizhi Dist.,
New Taipei City 22102, Taiwan (R.O.C.)
Title 
Size Document Number Rev
Date: Sheet 
of 
Bryce Canyon_IO Module 2
CLOCK TREE 
A3 
7 47Friday, December 08, 2017 
Bryce Canyon_IO Module 
http://www.wiwynn.com 
8F, 90, Sec.1, Xintai 5th Rd., Xizhi Dist.,
New Taipei City 22102, Taiwan (R.O.C.)
Title 
Size Document Number Rev
Date: Sheet 
of 
Bryce Canyon_IO Module 2
CLOCK TREE 
A3 
7 47Friday, December 08, 2017 
Bryce Canyon_IO Module 
http://www.wiwynn.com 
8F, 90, Sec.1, Xintai 5th Rd., Xizhi Dist.,
New Taipei City 22102, Taiwan (R.O.C.)



5
5
4
4
3
3
2
2
1
1
D D
C C
B B
A A
STACKUP INFORMATION
Title 
Size Document Number Rev
Date: Sheet 
of 
Bryce Canyon_IO Module 2
STACK UP 
A3 
8 47Friday, December 08, 2017 
Bryce Canyon_IO Module 
http://www.wiwynn.com 
8F, 90, Sec.1, Xintai 5th Rd., Xizhi Dist.,
New Taipei City 22102, Taiwan (R.O.C.)
Title 
Size Document Number Rev
Date: Sheet 
of 
Bryce Canyon_IO Module 2
STACK UP 
A3 
8 47Friday, December 08, 2017 
Bryce Canyon_IO Module 
http://www.wiwynn.com 
8F, 90, Sec.1, Xintai 5th Rd., Xizhi Dist.,
New Taipei City 22102, Taiwan (R.O.C.)
Title 
Size Document Number Rev
Date: Sheet 
of 
Bryce Canyon_IO Module 2
STACK UP 
A3 
8 47Friday, December 08, 2017 
Bryce Canyon_IO Module 
http://www.wiwynn.com 
8F, 90, Sec.1, Xintai 5th Rd., Xizhi Dist.,
New Taipei City 22102, Taiwan (R.O.C.)



5
5
4
4
3
3
2
2
1
1
D D
C C
B B
A A
I2C TOPOLOGY
BMC_A 
I2C_1 
I2C_IOM_SCL 
I2C_IOM_SDA 
I2C_2 
U2 
I2C_IOC_SCL 
I2C_IOC_SDA 
I2C_3 
Mono Lake_A 
I2C I2C_4 
I2C_SCC_SCL 
I2C_SCC_SDA 
I2C_BMC_COMP_SCL 
I2C_BMC_COMP_SDA 
I2C_BMC_COMP_ALERT_N 
I2C_7 
I2C_M2_1_SCL 
I2C_M2_1_SDA 
I2C_8 
I2C_9 
I2C_M2_2_SCL 
I2C_M2_2_SDA 
I2C_12 
OCP V2 
Mezzanine 
Card 
I2C_13 
I2C_MEZZ_OOB_SCL 
I2C_MEZZ_OOB_SDA 
I2C_MEZZ_ALERT_N 
I2C_DEBUG_SCL 
I2C_DEBUG_SDA 
OOB 
I2C_14 
I2C_TPM_SCL 
I2C_TPM_SDA 
Front DPB Rear DPB 
FRUID_EEPROM 
AT24C64 
ADDR: 0xA0 
U26 
SBL_SCL/SDA 
IOC 
SBL 
I2C_4(0x0A) 
U1 
U38 
EEPROM 
AT24C64 
ADDR: 0xA0 
SCC_A 
SENSORS 
I2C_SWITCH 
I2C_COMP_SCL 
I2C_COMP_SDA 
I2C_COMP_ALERT_N 
M.2_1 
M.2_2 
Type 5 only 
I2C_DPB_MISC_SCL 
I2C_DPB_MISC_SDA 
I2C_6 
        SENSORS 
(Temp*4 & FRUID EEPROM) 
I2C 
I2C_DPB_SCL 
I2C_DPB_SDA 
I2C_EXP_RMT_SCL 
I2C_EXP_RMT_SDA 
I2C_10 
I2C_11 
I2C_EXP_LOC_SCL 
I2C_EXP_LOC_SDA 
I2C 
I2C_SWITCH 
I2C_SWITCH 
EXP_A 
SCC_B 
I2C 
EXP_B 
TPM 
TPM1 
I2C_EXP_LOC_SCL_OUT 
I2C_EXP_LOC_SDA_OUT 
I2C_EXP_RMT_SCL_OUT 
I2C_EXP_RMT_SDA_OUT 
I2C_SWITCH 
I2C_DPB_SCL_OUT 
I2C_DPB_SDA_OUT 
IOM 
IO EXP I2C 
IO_EXP 
ADDR:0x40 DEBUG CARD 
ADDR: 0x40 
I2C_5 
I2C_MEZZ_FRU_SENSOR_SCL 
I2C_MEZZ_FRU_SENSOR_SDA 
TEMP SENSOR2 
TMP75 
ADDR: 0x94 
U27 
I2C 
HSC 
ADM1278 
ADDR: 0x20 
U35 
Title 
Size Document Number Rev
Date: Sheet 
of 
Bryce Canyon_IO Module 2
I2C TOPOLOGY 
A3 
9 47Friday, December 08, 2017 
Bryce Canyon_IO Module 
http://www.wiwynn.com 
8F, 90, Sec.1, Xintai 5th Rd., Xizhi Dist.,
New Taipei City 22102, Taiwan (R.O.C.)
Title 
Size Document Number Rev
Date: Sheet 
of 
Bryce Canyon_IO Module 2
I2C TOPOLOGY 
A3 
9 47Friday, December 08, 2017 
Bryce Canyon_IO Module 
http://www.wiwynn.com 
8F, 90, Sec.1, Xintai 5th Rd., Xizhi Dist.,
New Taipei City 22102, Taiwan (R.O.C.)
Title 
Size Document Number Rev
Date: Sheet 
of 
Bryce Canyon_IO Module 2
I2C TOPOLOGY 
A3 
9 47Friday, December 08, 2017 
Bryce Canyon_IO Module 
http://www.wiwynn.com 
8F, 90, Sec.1, Xintai 5th Rd., Xizhi Dist.,
New Taipei City 22102, Taiwan (R.O.C.)



5
5
4
4
3
3
2
2
1
1
D D
C C
B B
A A
UART TOPOLOGY
D Flip 
 Flop 
Mono Lake 
Tx 
Rx 
BMC 
Tx Rx 
BUFFER 
AND BUFFER UART MUX 
NC1 
NC2 
NO1 NO2 
UART1 UART5 
Tx Rx 
COM1 
COM2 USB CONN 
SEL 
GPI 
NC1/NO1 <-> COM1 
NC2/NO2 <-> COM2 
Pin8 
(Rx) 
Pin9 
(Tx) IO EXP Pin20 
Pin13 EXTRST 
GPI 
DEBUG_RST_BTN_N 
DEBUG_HDR_UART_SEL 
Pin4~11 
GPO LED_POSTCODE_0~7 
 Pin5 
(SCL) 
 Pin6 
(SDA) 
SCL 
SDA 
U34 
USB1 U100/U101 
U33 
U46 U32 
EXP_SDB_Tx 
EXP_SDB_Rx 
SCC 
Tx 
Rx 
UART2 
Title 
Size Document Number Rev
Date: Sheet 
of 
Bryce Canyon_IO Module 2
CLOCK DIAGRAM 
A3 
10 47Friday, December 08, 2017 
Bryce Canyon_IO Module 
http://www.wiwynn.com 
8F, 90, Sec.1, Xintai 5th Rd., Xizhi Dist.,
New Taipei City 22102, Taiwan (R.O.C.)
Title 
Size Document Number Rev
Date: Sheet 
of 
Bryce Canyon_IO Module 2
CLOCK DIAGRAM 
A3 
10 47Friday, December 08, 2017 
Bryce Canyon_IO Module 
http://www.wiwynn.com 
8F, 90, Sec.1, Xintai 5th Rd., Xizhi Dist.,
New Taipei City 22102, Taiwan (R.O.C.)
Title 
Size Document Number Rev
Date: Sheet 
of 
Bryce Canyon_IO Module 2
CLOCK DIAGRAM 
A3 
10 47Friday, December 08, 2017 
Bryce Canyon_IO Module 
http://www.wiwynn.com 
8F, 90, Sec.1, Xintai 5th Rd., Xizhi Dist.,
New Taipei City 22102, Taiwan (R.O.C.)



5
5
4
4
3
3
2
2
1
1
D D
C C
B B
A A
PCIE_COMP_TO_IOM_8_DP 
PCIE_COMP_TO_IOM_8_DN 
PCIE_IOM_TO_COMP_8_DP 
PCIE_IOM_TO_COMP_8_DN 
PCIE_COMP_TO_IOM_RST_2 
PCIE_COMP_TO_IOM_CLK_2_DP 
PCIE_COMP_TO_IOM_CLK_2_DN 
PCIE_COMP_TO_IOM_9_DP 
PCIE_COMP_TO_IOM_9_DN 
PCIE_IOM_TO_COMP_9_DP 
PCIE_IOM_TO_COMP_9_DN 
I2C_SCC_SCL 
I2C_SCC_SDA 
PCIE_COMP_TO_IOM_11_DP 
PCIE_COMP_TO_IOM_11_DN 
PCIE_IOM_TO_COMP_11_DP 
PCIE_IOM_TO_COMP_11_DN 
SCC_STBY_PWR_EN 
SCC_LOC_FULL_PWR_EN 
SCC_RMT_FULL_PWR_EN 
PCIE_COMP_TO_IOM_10_DP 
PCIE_COMP_TO_IOM_10_DN 
PCIE_IOM_TO_COMP_10_DP 
PCIE_IOM_TO_COMP_10_DN 
SCC_LOC_HEARTBEAT 
SCC_RMT_HEARTBEAT 
BMC_RMT_HEARTBEAT 
BMC_LOC_HEARTBEAT 
PCIE_COMP_TO_IOM_12_DP 
PCIE_COMP_TO_IOM_12_DN 
PCIE_IOM_TO_COMP_12_DP 
PCIE_IOM_TO_COMP_12_DN 
PCIE_COMP_TO_IOM_RST_3 
IOM_LOC_INS_N 
PCIE_COMP_TO_IOM_CLK_3_DP 
PCIE_COMP_TO_IOM_CLK_3_DN 
PCIE_COMP_TO_IOM_13_DP 
PCIE_COMP_TO_IOM_13_DN 
PCIE_IOM_TO_COMP_13_DP 
PCIE_IOM_TO_COMP_13_DN 
I2C_EXP_RMT_SCL 
I2C_EXP_RMT_SDA 
I2C_EXP_LOC_SCL 
I2C_EXP_LOC_SDA 
PCIE_COMP_TO_IOM_14_DP 
PCIE_COMP_TO_IOM_14_DN 
PCIE_IOM_TO_COMP_14_DP 
PCIE_IOM_TO_COMP_14_DN 
PCIE_COMP_TO_IOM_15_DP 
PCIE_COMP_TO_IOM_15_DN 
PCIE_IOM_TO_COMP_15_DP 
PCIE_IOM_TO_COMP_15_DN 
PCIE_COMP_TO_IOM_16_DP 
PCIE_COMP_TO_IOM_16_DN 
PCIE_IOM_TO_COMP_16_DP 
PCIE_IOM_TO_COMP_16_DN 
PCIE_COMP_TO_IOM_RST_4 
I2C_BMC_COMP_ALERT_N 
PCIE_COMP_TO_IOM_CLK_4_DP 
PCIE_COMP_TO_IOM_CLK_4_DN 
PCIE_COMP_TO_IOM_17_DP 
PCIE_COMP_TO_IOM_17_DN 
PCIE_IOM_TO_COMP_17_DP 
PCIE_IOM_TO_COMP_17_DN 
I2C_BMC_COMP_SCL 
I2C_BMC_COMP_SDA 
SLOTID_0 
SLOTID_1 
PCIE_COMP_TO_IOM_18_DP 
PCIE_COMP_TO_IOM_18_DN 
PCIE_IOM_TO_COMP_18_DP 
PCIE_IOM_TO_COMP_18_DN 
DPB_MISC_ALERT 
PCIE_COMP_TO_IOM_19_DP 
PCIE_COMP_TO_IOM_19_DN 
PCIE_IOM_TO_COMP_19_DP 
PCIE_IOM_TO_COMP_19_DN 
COMP_PWR_EN 
PCIE_COMP_TO_IOM_20_DP 
PCIE_COMP_TO_IOM_20_DN 
PCIE_IOM_TO_COMP_20_DP 
PCIE_IOM_TO_COMP_20_DN 
COMP_POWER_FAIL_N 
SYS_RESET_N 
COMP_TO_BMC_RESET 
PCIE_COMP_TO_IOM_21_DP 
PCIE_COMP_TO_IOM_21_DN 
PCIE_IOM_TO_COMP_21_DP 
PCIE_IOM_TO_COMP_21_DN 
COMP_PWR_BTN_N 
I2C_DPB_SCL 
I2C_DPB_SDA 
PCIE_COMP_TO_IOM_22_DP 
PCIE_COMP_TO_IOM_22_DN 
PCIE_IOM_TO_COMP_22_DP 
PCIE_IOM_TO_COMP_22_DN 
ENCL_FAULT_LED 
EXP_SPARE_0 
EXP_SPARE_1 
PCIE_COMP_TO_IOM_23_DP 
PCIE_COMP_TO_IOM_23_DN 
PCIE_IOM_TO_COMP_23_DP 
PCIE_IOM_TO_COMP_23_DN 
PWM_OUT_ZONE_D 
COMP_SPARE_0 
COMP_SPARE_1 
PWM_OUT_ZONE_C 
SYS_PWR_LED 
UART_SDB_RX 
UART_SDB_TX 
SCC_RMT_TYPE_0 
BMC_TO_EXP_RESET_N 
I2C_DPB_MISC_SCL 
I2C_DPB_MISC_SDA 
P12V_A_PGOOD 
USB_COMP_DP 
USB_COMP_DN 
UART_COMP_TX 
UART_COMP_RX 
COMP_FAST_THROTTLE_N 
IOM_MATED_N 
P12V_IOM P12V_IOM 
PCIE_COMP_TO_IOM_8_DP 36 
PCIE_COMP_TO_IOM_8_DN 36 
PCIE_IOM_TO_COMP_8_DP 36 
PCIE_IOM_TO_COMP_8_DN 36 
PCIE_COMP_TO_IOM_RST_2 39 
PCIE_COMP_TO_IOM_CLK_2_DP 36 
PCIE_COMP_TO_IOM_CLK_2_DN 36 
PCIE_COMP_TO_IOM_9_DP 36 
PCIE_COMP_TO_IOM_9_DN 36 
PCIE_IOM_TO_COMP_9_DP 36 
PCIE_IOM_TO_COMP_9_DN 36 
I2C_SCC_SCL 18 
I2C_SCC_SDA 18 
PCIE_COMP_TO_IOM_11_DP 36
PCIE_COMP_TO_IOM_11_DN 36
PCIE_IOM_TO_COMP_11_DP 36
PCIE_IOM_TO_COMP_11_DN 36
SCC_STBY_PWR_EN 21 
SCC_LOC_FULL_PWR_EN 21
PCIE_COMP_TO_IOM_10_DP 36 
PCIE_COMP_TO_IOM_10_DN 36 
PCIE_IOM_TO_COMP_10_DP 36 
PCIE_IOM_TO_COMP_10_DN 36 
SCC_LOC_HEARTBEAT 22 
SCC_RMT_HEARTBEAT 22 
BMC_RMT_HEARTBEAT 22 
PCIE_COMP_TO_IOM_12_DP 36 
PCIE_COMP_TO_IOM_12_DN 36 
PCIE_IOM_TO_COMP_12_DP 36 
PCIE_IOM_TO_COMP_12_DN 36 
IOM_LOC_INS_N 21 
PCIE_COMP_TO_IOM_13_DP 36 
PCIE_COMP_TO_IOM_13_DN 36 
PCIE_IOM_TO_COMP_13_DP 36 
PCIE_IOM_TO_COMP_13_DN 36 
I2C_EXP_RMT_SCL 18 
I2C_EXP_RMT_SDA 18 
I2C_EXP_LOC_SCL 18 
I2C_EXP_LOC_SDA 18 
PCIE_COMP_TO_IOM_14_DP 36 
PCIE_COMP_TO_IOM_14_DN 36 
PCIE_IOM_TO_COMP_14_DP 36 
PCIE_IOM_TO_COMP_14_DN 36 
PCIE_COMP_TO_IOM_15_DP 36
PCIE_COMP_TO_IOM_15_DN 36
PCIE_IOM_TO_COMP_15_DP 36
PCIE_IOM_TO_COMP_15_DN 36
PCIE_COMP_TO_IOM_16_DP 12 
PCIE_COMP_TO_IOM_16_DN 12 
PCIE_IOM_TO_COMP_16_DP 12 
PCIE_IOM_TO_COMP_16_DN 12 
PCIE_COMP_TO_IOM_RST_4 12,14,21,26 
I2C_BMC_COMP_ALERT_N 18 
PCIE_COMP_TO_IOM_CLK_4_DP 12 
PCIE_COMP_TO_IOM_CLK_4_DN 12 
PCIE_COMP_TO_IOM_17_DP 12 
PCIE_COMP_TO_IOM_17_DN 12 
PCIE_IOM_TO_COMP_17_DP 12 
PCIE_IOM_TO_COMP_17_DN 12 
I2C_BMC_COMP_SCL 18 
I2C_BMC_COMP_SDA 18 
SLOTID_0 22 
SLOTID_1 22 
PCIE_COMP_TO_IOM_18_DP 12 
PCIE_COMP_TO_IOM_18_DN 12 
PCIE_IOM_TO_COMP_18_DP 12 
PCIE_IOM_TO_COMP_18_DN 12 
DPB_MISC_ALERT 18 
PCIE_COMP_TO_IOM_19_DP 12
PCIE_COMP_TO_IOM_19_DN 12
PCIE_IOM_TO_COMP_19_DP 12
PCIE_IOM_TO_COMP_19_DN 12
COMP_PWR_EN 18,22 
PCIE_COMP_TO_IOM_20_DP 12 
PCIE_COMP_TO_IOM_20_DN 12 
PCIE_IOM_TO_COMP_20_DP 12 
PCIE_IOM_TO_COMP_20_DN 12 
COMP_POWER_FAIL_N 22 
SYS_RESET_N 18 
COMP_TO_BMC_RESET 18 
PCIE_COMP_TO_IOM_21_DP 12 
PCIE_COMP_TO_IOM_21_DN 12 
PCIE_IOM_TO_COMP_21_DP 12 
PCIE_IOM_TO_COMP_21_DN 12 
COMP_PWR_BTN_N 20 
I2C_DPB_SCL 18 
I2C_DPB_SDA 18 
PCIE_COMP_TO_IOM_22_DP 12 
PCIE_COMP_TO_IOM_22_DN 12 
PCIE_IOM_TO_COMP_22_DP 12 
PCIE_IOM_TO_COMP_22_DN 12 
ENCL_FAULT_LED 22 
EXP_SPARE_0 21 
EXP_SPARE_1 21 
PCIE_COMP_TO_IOM_23_DP 12
PCIE_COMP_TO_IOM_23_DN 12
PCIE_IOM_TO_COMP_23_DP 12
PCIE_IOM_TO_COMP_23_DN 12
PWM_OUT_ZONE_D 22 
COMP_SPARE_0 22 
COMP_SPARE_1 22 
PWM_OUT_ZONE_C 22 
SYS_PWR_LED 20 
UART_SDB_RX 26 
UART_SDB_TX 26 
SCC_RMT_FULL_PWR_EN 21
BMC_LOC_HEARTBEAT 22 
SCC_RMT_TYPE_0 21 
BMC_TO_EXP_RESET_N 18 
I2C_DPB_MISC_SCL 18 
I2C_DPB_MISC_SDA 18 
P12V_A_PGOOD 21,27 
USB_COMP_DP 14 
USB_COMP_DN 14 
UART_COMP_RX 26 
UART_COMP_TX 26 
COMP_FAST_THROTTLE_N 22 
IOM_MATED_N 27 
Title 
Size Document Number Rev
Date: Sheet 
of 
Bryce Canyon_IO Module 2
 XCEDE CONNECTOR 
A3 
11 47 Friday, December 08, 2017 
Bryce Canyon_IO Module 
http://www.wiwynn.com 
8F, 90, Sec.1, Xintai 5th Rd., Xizhi Dist.,
New Taipei City 22102, Taiwan (R.O.C.)
Title 
Size Document Number Rev
Date: Sheet 
of 
Bryce Canyon_IO Module 2
 XCEDE CONNECTOR 
A3 
11 47 Friday, December 08, 2017 
Bryce Canyon_IO Module 
http://www.wiwynn.com 
8F, 90, Sec.1, Xintai 5th Rd., Xizhi Dist.,
New Taipei City 22102, Taiwan (R.O.C.)
Title 
Size Document Number Rev
Date: Sheet 
of 
Bryce Canyon_IO Module 2
 XCEDE CONNECTOR 
A3 
11 47 Friday, December 08, 2017 
Bryce Canyon_IO Module 
http://www.wiwynn.com 
8F, 90, Sec.1, Xintai 5th Rd., Xizhi Dist.,
New Taipei City 22102, Taiwan (R.O.C.)
1 OF 8 CN1A 
AMP-CONN200-13R-4-GP 
A1 A1 
B1 B1 
GND1 GND1 
C1 C1 
D1 D1 
GND2 GND2 
E1 E1 
F1 F1 
GND3 GND3 
G1 G1 
H1 H1 
GND4 GND4 
GND5 GND5 
A2 A2 
B2 B2 
GND6 GND6 
C2 C2 
D2 D2 
GND7 GND7 
E2 E2 
F2 F2 
GND8 GND8 
G2 G2 
H2 H2 
GND9 GND9 
NP1 NP1 NP2 NP2 
5 OF 8 CN1E 
AMP-CONN200-13R-4-GP 
A9 A9 
B9 B9 
GND37 GND37 
C9 C9 
D9 D9 
GND38 GND38 
E9 E9 
F9 F9 
GND39 GND39 
G9 G9 
H9 H9 
GND40 GND40 
GND41 GND41 
A10 A10 
B10 B10 
GND42 GND42 
C10 C10 
D10 D10 
GND43 GND43 
E10 E10 
F10 F10 
GND44 GND44 
G10 G10 
H10 H10 
GND45 GND45 
2 OF 8 CN1B 
AMP-CONN200-13R-4-GP 
A3 A3 
B3 B3 
GND10 GND10 
C3 C3 
D3 D3 
GND11 GND11 
E3 E3 
F3 F3 
GND12 GND12 
G3 G3 
H3 H3 
GND13 GND13 
GND14 GND14 
A4 A4 
B4 B4 
GND15 GND15 
C4 C4 
D4 D4 
GND16 GND16 
E4 E4 
F4 F4 
GND17 GND17 
G4 G4 
H4 H4 
GND18 GND18 
4 OF 8 CN1D 
AMP-CONN200-13R-4-GP 
A7 A7 
B7 B7 
GND28 GND28 
C7 C7 
D7 D7 
GND29 GND29 
E7 E7 
F7 F7 
GND30 GND30 
G7 G7 
H7 H7 
GND31 GND31 
GND32 GND32 
A8 A8 
B8 B8 
GND33 GND33 
C8 C8 
D8 D8 
GND34 GND34 
E8 E8 
F8 F8 
GND35 GND35 
G8 G8 
H8 H8 
GND36 GND36 
6 OF 8 CN1F 
AMP-CONN200-13R-4-GP 
A11 A11 
B11 B11 
GND46 GND46 
C11 C11 
D11 D11 
GND47 GND47 
E11 E11 
F11 F11 
GND48 GND48 
G11 G11 
H11 H11 
GND49 GND49 
GND50 GND50 
A12 A12 
B12 B12 
GND51 GND51 
C12 C12 
D12 D12 
GND52 GND52 
E12 E12 
F12 F12 
GND53 GND53 
G12 G12 
H12 H12 
GND54 GND54 
TP2 1
3 OF 8 CN1C 
AMP-CONN200-13R-4-GP 
A5 A5 
B5 B5 
GND19 GND19 
C5 C5 
D5 D5 
GND20 GND20 
E5 E5 
F5 F5 
GND21 GND21 
G5 G5 
H5 H5 
GND22 GND22 
GND23 GND23 
A6 A6 
B6 B6 
GND24 GND24 
C6 C6 
D6 D6 
GND25 GND25 
E6 E6 
F6 F6 
GND26 GND26 
G6 G6 
H6 H6 
GND27 GND27 
8 OF 8 CN1H 
AMP-CONN200-13R-4-GP 
A15 A15 
B15 B15 
GND64 GND64 
C15 C15 
D15 D15 
GND65 GND65 
E15 E15 
F15 F15 
GND66 GND66 
G15 G15 
H15 H15 
GND67 GND67 
GND68 GND68 
A16 A16 
B16 B16 
GND69 GND69 
C16 C16 
D16 D16 
GND70 GND70 
E16 E16 
F16 F16 
GND71 GND71 
G16 G16 
H16 H16 
GND72 GND72 
TP1 1
7 OF 8 CN1G 
AMP-CONN200-13R-4-GP 
A13 A13 
B13 B13 
GND55 GND55 
C13 C13 
D13 D13 
GND56 GND56 
E13 E13 
F13 F13 
GND57 GND57 
G13 G13 
H13 H13 
GND58 GND58 
GND59 GND59 
A14 A14 
B14 B14 
GND60 GND60 
C14 C14 
D14 D14 
GND61 GND61 
E14 E14 
F14 F14 
GND62 GND62 
G14 G14 
H14 H14 
GND63 GND63 
TP3 1



5
5
4
4
3
3
2
2
1
1
D D
C C
B B
A A
OCP2.0 MEZZ_A
I2C_MEZZ_ALERT_R_N 
PCIE_COMP_TO_IOM_RST_4_R 
NCSI_RXD1_R 
NCSI_RXD0_R 
PCIE_IOM_TO_COMP_16_DN 
PCIE_IOM_TO_COMP_16_DP 
I2C_MEZZ_FRU_SENSOR_SDA 
I2C_MEZZ_FRU_SENSOR_SCL 
PCIE_WAKE_N 
MEZZA_PRSNT1_N 
NCSI_RCLK 
NCSI_RCSDV_R 
NCSI_TXEN_R 
MEZZ_A_PRSNT_120_N 
PCIE_COMP_TO_IOM_16_DN 
PCIE_COMP_TO_IOM_16_DP 
NCSI_RX_ER_R 
PCIE_COMP_TO_IOM_17_DN 
PCIE_COMP_TO_IOM_17_DP 
PCIE_COMP_TO_IOM_18_DN 
PCIE_COMP_TO_IOM_18_DP 
PCIE_COMP_TO_IOM_19_DN 
PCIE_COMP_TO_IOM_19_DP 
PCIE_COMP_TO_IOM_20_DN 
PCIE_COMP_TO_IOM_20_DP 
PCIE_COMP_TO_IOM_21_DN 
PCIE_COMP_TO_IOM_21_DP 
PCIE_COMP_TO_IOM_22_DN 
PCIE_COMP_TO_IOM_22_DP 
PCIE_COMP_TO_IOM_23_DN 
PCIE_COMP_TO_IOM_23_DP 
PCIE_IOM_TO_COMP_17_DN 
PCIE_IOM_TO_COMP_17_DP 
PCIE_IOM_TO_COMP_18_DN 
PCIE_IOM_TO_COMP_18_DP 
PCIE_IOM_TO_COMP_19_DN 
PCIE_IOM_TO_COMP_19_DP 
PCIE_IOM_TO_COMP_20_DP 
PCIE_IOM_TO_COMP_21_DN 
PCIE_IOM_TO_COMP_21_DP 
PCIE_IOM_TO_COMP_22_DN 
PCIE_IOM_TO_COMP_22_DP 
PCIE_IOM_TO_COMP_23_DN 
PCIE_IOM_TO_COMP_23_DP 
PCIE_IOM_TO_COMP_20_DN 
PCIE_COMP_TO_IOM_CLK_4_DP 
PCIE_COMP_TO_IOM_CLK_4_DN 
PCIE_COMP_TO_IOM_16_DP 
PCIE_COMP_TO_IOM_16_DN 
PCIE_COMP_TO_IOM_17_DP 
PCIE_COMP_TO_IOM_17_DN 
PCIE_COMP_TO_IOM_18_DN 
PCIE_COMP_TO_IOM_18_DP 
PCIE_COMP_TO_IOM_19_DP 
PCIE_COMP_TO_IOM_19_DN 
PCIE_COMP_TO_IOM_20_DP 
PCIE_COMP_TO_IOM_20_DN 
PCIE_COMP_TO_IOM_21_DN 
PCIE_COMP_TO_IOM_21_DP 
PCIE_COMP_TO_IOM_22_DN 
PCIE_COMP_TO_IOM_22_DP 
PCIE_COMP_TO_IOM_23_DN 
PCIE_COMP_TO_IOM_23_DP 
PCIE_IOM_TO_COMP_16_DP 
PCIE_IOM_TO_COMP_16_DN 
PCIE_IOM_TO_COMP_17_DP 
PCIE_IOM_TO_COMP_17_DN 
PCIE_IOM_TO_COMP_18_DN 
PCIE_IOM_TO_COMP_18_DP 
PCIE_IOM_TO_COMP_19_DP 
PCIE_IOM_TO_COMP_19_DN 
PCIE_IOM_TO_COMP_20_DP 
PCIE_IOM_TO_COMP_20_DN 
PCIE_IOM_TO_COMP_21_DN 
PCIE_IOM_TO_COMP_21_DP 
PCIE_IOM_TO_COMP_22_DN 
PCIE_IOM_TO_COMP_22_DP 
PCIE_IOM_TO_COMP_23_DN 
PCIE_IOM_TO_COMP_23_DP 
MEZZA_PRSNT1_N 
MEZZ_A_PRSNT_120_N 
I2C_MEZZ_OOB_SCL 
I2C_MEZZ_OOB_SDA 
PCIE_COMP_TO_IOM_CLK_4_DN 
PCIE_COMP_TO_IOM_CLK_4_DP 
P5V_STBY 
P12V_STBY 
P3V3 
P3V3_STBY 
P3V3_STBY 
P3V3 
P3V3_STBY 
P3V3_STBY 
P3V3_STBY 
P3V3_STBY 
P12V_STBY P5V_STBY P3V3_STBY 
PCIE_IOM_TO_COMP_16_DN 11 
PCIE_IOM_TO_COMP_16_DP 11 
PCIE_WAKE_N 22 
PCIE_COMP_TO_IOM_16_DP 11 
PCIE_COMP_TO_IOM_16_DN 11 
I2C_MEZZ_ALERT_N 21 
NCSI_RXD0 21 
NCSI_RXD1 21 
NCSI_TXEN 21,24 
PCIE_COMP_TO_IOM_RST_4 11,14,21,26 
NCSI_RCSDV 21 
NCSI_RCLK 21 
NCSI_TXD0 21,24 
NCSI_TXD1 21,24 
NCSI_RX_ER 21 
I2C_MEZZ_FRU_SENSOR_SCL 20 
I2C_MEZZ_FRU_SENSOR_SDA 20 
PCIE_COMP_TO_IOM_CLK_4_DP 11 
PCIE_COMP_TO_IOM_CLK_4_DN 11 
PCIE_COMP_TO_IOM_17_DN 11 
PCIE_COMP_TO_IOM_17_DP 11 
PCIE_COMP_TO_IOM_18_DP 11 
PCIE_COMP_TO_IOM_18_DN 11 
PCIE_COMP_TO_IOM_19_DN 11 
PCIE_COMP_TO_IOM_19_DP 11 
PCIE_COMP_TO_IOM_20_DP 11 
PCIE_COMP_TO_IOM_20_DN 11 
PCIE_COMP_TO_IOM_21_DN 11 
PCIE_COMP_TO_IOM_21_DP 11 
PCIE_COMP_TO_IOM_22_DN 11 
PCIE_COMP_TO_IOM_22_DP 11 
PCIE_COMP_TO_IOM_23_DP 11 
PCIE_COMP_TO_IOM_23_DN 11 
PCIE_IOM_TO_COMP_17_DN 11 
PCIE_IOM_TO_COMP_17_DP 11 
PCIE_IOM_TO_COMP_18_DN 11 
PCIE_IOM_TO_COMP_18_DP 11 
PCIE_IOM_TO_COMP_19_DN 11 
PCIE_IOM_TO_COMP_19_DP 11 
PCIE_IOM_TO_COMP_20_DN 11 
PCIE_IOM_TO_COMP_20_DP 11 
PCIE_IOM_TO_COMP_21_DN 11 
PCIE_IOM_TO_COMP_21_DP 11 
PCIE_IOM_TO_COMP_22_DP 11 
PCIE_IOM_TO_COMP_22_DN 11 
PCIE_IOM_TO_COMP_23_DN 11 
PCIE_IOM_TO_COMP_23_DP 11 
CONN_A_PRSNTA 21 
I2C_MEZZ_OOB_SCL 20 
I2C_MEZZ_OOB_SDA 20 
Title 
Size Document Number Rev
Date: Sheet 
of 
Bryce Canyon_IO Module 2
OCP2.0_MEZZ CONN_A 
A3 
12 47 Friday, December 08, 2017 
Bryce Canyon_IO Module 
http://www.wiwynn.com 
8F, 90, Sec.1, Xintai 5th Rd., Xizhi Dist.,
New Taipei City 22102, Taiwan (R.O.C.)
Title 
Size Document Number Rev
Date: Sheet 
of 
Bryce Canyon_IO Module 2
OCP2.0_MEZZ CONN_A 
A3 
12 47 Friday, December 08, 2017 
Bryce Canyon_IO Module 
http://www.wiwynn.com 
8F, 90, Sec.1, Xintai 5th Rd., Xizhi Dist.,
New Taipei City 22102, Taiwan (R.O.C.)
Title 
Size Document Number Rev
Date: Sheet 
of 
Bryce Canyon_IO Module 2
OCP2.0_MEZZ CONN_A 
A3 
12 47 Friday, December 08, 2017 
Bryce Canyon_IO Module 
http://www.wiwynn.com 
8F, 90, Sec.1, Xintai 5th Rd., Xizhi Dist.,
New Taipei City 22102, Taiwan (R.O.C.)VIA8 
85OHM-8L-1D6MM-L16L18-GP 
P2
N3 GND 4
GND 1
C29 
SC2D2U25V5KX-2-GP 
2.2uF 
25V 
10% 
0805 
X7R 
1 2
VIA16 
85OHM-8L-1D6MM-L16L18-GP 
P2
N3 GND 4
GND 1
R64 
10KR2F-2-GP 
10k ohm 
1/16W 
1% 
0402 
1 2
VIA7 
85OHM-8L-1D6MM-L16L18-GP 
P2
N3 GND 4
GND 1
VIA14 
85OHM-8L-1D6MM-L16L18-GP 
P2
N3 GND 4
GND 1
VIA10 
85OHM-8L-1D6MM-L16L18-GP 
P2
N3 GND 4
GND 1
VIA15 
85OHM-8L-1D6MM-L16L18-GP 
P2
N3 GND 4
GND 1
C512 
SC10U16V5KX-7-GP-U 
10uF 
16V 
10% 
0805 
X7R 
1 2
VIA2 
85OHM-8L-1D6MM-L16L18-GP 
P2
N3 GND 4
GND 1
VIA3 
85OHM-8L-1D6MM-L16L18-GP 
P2
N3 GND 4
GND 1
C28 
SC2D2U25V5KX-2-GP 
2.2uF 
25V 
10% 
0805 
X7R 
1 2
Q25 
2N7002K-1-GP 
G
D S
VIA9 
85OHM-8L-1D6MM-L16L18-GP 
P2
N3 GND 4
GND 1
VIA12 
85OHM-8L-1D6MM-L16L18-GP 
P2
N3 GND 4
GND 1
R14 0 ohm 0402 12
R10 
0R2J-2-GP 
0 ohm 
1/16W 
5% 
0402 
1 2
R4 0 ohm 0402 12
VIA4 
85OHM-8L-1D6MM-L16L18-GP 
P2
N3 GND 4
GND 1
MEZZ1 
FCI-CONN120-GP-U1 
NP1 
NP2 
1
2
3
4
5
6
7
8
9
10 
11 
12 
13 
14 
15 
16 
17 
18 
19 
20 
21 
22 
23 
24 
25 
26 
27 
28 
29 
30 
31 
32 
33 
34 
35 
36 
37 
38 
39 
40 
41 
42 
43 
44 
45 
46 
47 
48 
49 
50 
51 
52 
53 
54 
55 
56 
57 
58 
59 
60 
61 
62 
63 
64 
65 
66 
67 
68 
69 
70 
71 
72 
73 
74 
75 
76 
77 
78 
79 
80 
81 
82 
83 
84 
85 
86 
87 
88 
89 
90 
91 
92 
93 
94 
95 
96 
97 
98 
99 
100 
101 
102 
103 
104 
105 
106 
107 
108 
109 
110 
111 
112 
113 
114 
115 
116 
117 
118 
119 
120 
C25 
SC2D2U25V5KX-2-GP 
2.2uF 
25V 
10% 
0805 
X7R 
1 2
VIA13 
85OHM-8L-1D6MM-L16L18-GP 
P2
N3 GND 4
GND 1
R9 0 ohm 0402 12
R7 0 ohm 0402 12
C511 
SC10U16V5KX-7-GP-U 
10uF 
16V 
10% 
0805 
X7R 
1 2
VIA5 
85OHM-8L-1D6MM-L16L18-GP 
P2
N3 GND 4
GND 1
VIA1 
85OHM-8L-1D6MM-L16L18-GP 
P2
N3 GND 4
GND 1
R3 
4K7R2F-GP 
4.7k ohm 
1/16W 
1% 
0402 
12
R16 
10KR2F-2-GP 
NOPOP 
10k ohm 
1/16W 
1% 
0402 
1 2
R728 
4K7R2F-GP 
4.7k ohm 
1/16W 
1% 
0402 
12
R5 0 ohm 0402 12
R15 0 ohm 0402 12
VIA11 
85OHM-8L-1D6MM-L16L18-GP 
P2
N3 GND 4
GND 1
VIA6 
85OHM-8L-1D6MM-L16L18-GP 
P2
N3 GND 4
GND 1
R8 0 ohm 0402 12
VIA25 
85OHM-8L-1D6MM-L16L18-GP 
P2
N3 GND 4
GND 1



5
5
4
4
3
3
2
2
1
1
D D
C C
B B
A A
Title 
Size Document Number Rev
Date: Sheet 
of 
Bryce Canyon_IO Module 2
RESERVE 
A3 
13 47 Friday, December 08, 2017 
Bryce Canyon_IO Module 
http://www.wiwynn.com 
8F, 90, Sec.1, Xintai 5th Rd., Xizhi Dist.,
New Taipei City 22102, Taiwan (R.O.C.)
Title 
Size Document Number Rev
Date: Sheet 
of 
Bryce Canyon_IO Module 2
RESERVE 
A3 
13 47 Friday, December 08, 2017 
Bryce Canyon_IO Module 
http://www.wiwynn.com 
8F, 90, Sec.1, Xintai 5th Rd., Xizhi Dist.,
New Taipei City 22102, Taiwan (R.O.C.)
Title 
Size Document Number Rev
Date: Sheet 
of 
Bryce Canyon_IO Module 2
RESERVE 
A3 
13 47 Friday, December 08, 2017 
Bryce Canyon_IO Module 
http://www.wiwynn.com 
8F, 90, Sec.1, Xintai 5th Rd., Xizhi Dist.,
New Taipei City 22102, Taiwan (R.O.C.)



5
5
4
4
3
3
2
2
1
1
D D
C C
B B
A A
30Ohm@100MHz 
Imax=3A 
DCR=30m ohm 
1000PF 
2KV 
1206 
X7R 
USB_P1_F_DN1 
USB_P1_F_DP1 
PLLFILT 
CRFILT 
CRFILT 
PLLFILT 
RBIAS 
USB_HUB_XTAL_OUT 
USB_HUB_XTAL_IN USB_P1_DN 
USB_P1_DP 
USB_OCS_N1 
USB_OCS_N2 
USB_OCS_N3 
USB_OCS_N4 
USB_OCS_N3 
USB_OCS_N4 
USB_OCS_N2 
TP_USB_SDA 
USB_EN_4 
USB_EN_3 
USB_EN_2 
USB_EN_1 
USB_SUSP_IND 
USB_SUSP_IND 
USB_EN_1 
USB_EN_2 
CFG_SEL0 
CFG_SEL1 
VBUS_DET 
VBUS_DET 
USB_RESET_N 
CFG_SEL0 
USB_RESET_N 
CFG_SEL1 
USB_P1_DP 
USB_P1_DN 
USB_HUB_XTAL_OUT 
USB_HUB_XTAL_IN 
USB_OCS_N1 
USB_OCS_N1 USB_EN_1 
USB_P1_F_DP1 
USB_P1_F_DN1 
UART_IOM_RX 
UART_IOM_TX 
I2C_DEBUG_SDA 
I2C_DEBUG_SCL 
DEBUG_CARD_PRSNT 
USB_EN_3 
USB_EN_4 
P5V_VBUS_CONN 
USB_CONN_GND 
UART_IOM_RX 
UART_IOM_TX 
I2C_DEBUG_SDA 
I2C_DEBUG_SCL 
I2C_DEBUG_SDA 
I2C_DEBUG_SCL 
P5V_VBUS_CONN 
P5V_USB 
P3V3_STBY 
P3V3_STBY 
P3V3_STBY P3V3_STBY P3V3_STBY P3V3_STBY 
P5V_STBY 
P3V3_STBY 
P3V3_STBY P3V3_STBY P3V3_STBY P3V3_STBY P3V3_STBY P3V3_STBY P3V3_STBY P3V3_STBY
P5V_USB 
P5V_USB 
P3V3_STBY 
USB_P2_DP 22 
USB_P2_DN 22 
USB_P3_DP 22 
USB_P3_DN 22 
PCIE_COMP_TO_IOM_RST_4 11,12,21,26 
USB_OCS_N1 20 
UART_IOM_RX 26 
UART_IOM_TX 26 
I2C_DEBUG_SDA 26 
I2C_DEBUG_SCL 26 
USB_COMP_DP 11 
USB_COMP_DN 11 
DEBUG_CARD_PRSNT 26 
Title 
Size Document Number Rev
Date: Sheet 
of 
Bryce Canyon_IO Module 2
USB2.0*1 
A3 
14 47Friday, December 08, 2017 
Bryce Canyon_IO Module 
http://www.wiwynn.com 
8F, 90, Sec.1, Xintai 5th Rd., Xizhi Dist.,
New Taipei City 22102, Taiwan (R.O.C.)
Title 
Size Document Number Rev
Date: Sheet 
of 
Bryce Canyon_IO Module 2
USB2.0*1 
A3 
14 47Friday, December 08, 2017 
Bryce Canyon_IO Module 
http://www.wiwynn.com 
8F, 90, Sec.1, Xintai 5th Rd., Xizhi Dist.,
New Taipei City 22102, Taiwan (R.O.C.)
Title 
Size Document Number Rev
Date: Sheet 
of 
Bryce Canyon_IO Module 2
USB2.0*1 
A3 
14 47Friday, December 08, 2017 
Bryce Canyon_IO Module 
http://www.wiwynn.com 
8F, 90, Sec.1, Xintai 5th Rd., Xizhi Dist.,
New Taipei City 22102, Taiwan (R.O.C.)
R40 
4K7R2F-GP 
NOPOP 
4.7k ohm 
1/16W 
1% 
0402 
1 2
D15 
PESD5V0S1BL-1-GP 
1 2
C21 
SC1U16V3KX-5GP 
1uF 
16V 
10% 
0603 
X7R 
1 2
C11 
SC1U16V2KX-7-GP 
1uF 
16V 
10% 
0402 
X6S 
1 2
C16 
SC1U16V3KX-5GP 
1uF 
16V 
10% 
0603 
X7R 
1 2
USB1 
SKT-USB13-246-GP 
VBUS 1
D- 2
D+ 3
GND 4
STDA_SSRX- 5
STDA_SSRX+ 6
GND_DRAIN 7
STDA_SSTX- 8
STDA_SSTX+ 9
GND 10 
GND 11 
GND 12 
GND 13 
X1 
XTAL-24MHZ-87-GP 
4 1
23
C15 
SC1U16V3KX-5GP 
1uF 
16V 
10% 
0603 
X7R 
1 2
R23 
4K7R2F-GP 
4.7k ohm 
1/16W 
1% 
0402 
1 2
C13 
SC1U16V3KX-5GP 
1uF 
16V 
10% 
0603 
X7R 
1 2
D18 
PESD5V0F1BL-GP 
12
R22 
4K7R2F-GP 
4.7k ohm 
1/16W 
1% 
0402 
1 2
R34 
4K7R2F-GP 
4.7k ohm 
1/16W 
1% 
0402 
1 2
C18 
SC1U16V3KX-5GP 
1uF 
16V 
10% 
0603 
X7R 
1 2
R18 
4K7R2F-GP 
NOPOP 
4.7k ohm 
1/16W 
1% 
0402 
1 2
R38 0 ohm 0402 12
C14 
SC1KP50V2KX-1GP 
1000pF 
50V 
10% 
0402 
X7R 
NOPOP 
1 2
R37 
1MR2F-GP 
1M ohm 
1/16W 
1% 
0402 
1 2
D17 
PESD5V0S1BL-1-GP 
1 2
R27 1MR2F-GP 
1M ohm 1/16W 1% 0402 
1 2
R29 
4K7R2F-GP 
4.7k ohm 
1/16W 
1% 
0402 
1 2
R46 0 ohm 0402 12
R31 
4K7R2F-GP 
4.7k ohm 
1/16W 
1% 
0402 
1 2
C325 
ST150U16VDM-3-GP 
150uF 
16V 
Irp=1.8A 
ESR= 55mOhm 
Tmax=105C 
1 2
R21 
4K7R2F-GP 
NOPOP 
4.7k ohm 
1/16W 
1% 
0402 
1 2
R43
4K7R2F-GP
NOPOP
4.7k ohm
1/16W
1%
0402
1 2
D14 
PESD5V0S1BL-1-GP 
1 2
R42 
4K7R2F-GP 
NOPOP 
4.7k ohm 
1/16W 
1% 
0402 
1 2
C20 
SC18P50V2JN-1-GP 
18pF 
50V 
5% 
0402 
NPO 
1 2
D13 
PESD5V0S1BL-1-GP 
1 2
C12 
SC1U16V2KX-7-GP 
1uF 
16V 
10% 
0402 
X6S 
1 2
R50 
4K7R2F-GP 
4.7k ohm 
1/16W 
1% 
0402 
NOPOP 
1 2
R41 
4K7R2F-GP 
NOPOP 
4.7k ohm 
1/16W 
1% 
0402 
1 2
U98 
TPS2065DBVT-GP 
OUT 1
GND 2
OC# 3 EN 4
IN 5
C17 
SC18P50V2JN-1-GP 
18pF 
50V 
5% 
0402 
NPO 
1 2
R33 
4K7R2F-GP 
4.7k ohm 
1/16W 
1% 
0402 
1 2
R28 
12KR2J-L-GP 
12k ohm 
1/16W 
5% 
0402 
1 2
U99 
USB2514B-AEZC-TR-GP-U USBDM_DN1/PRT_DIS_M1 1 USBDP_DN1/PRT_DIS_P1 2
USBDM_DN2/PRT_DIS_M2 3 USBDP_DN2/PRT_DIS_P2 4
VDDA33 5
USBDM_DN3/PRT_DIS_M3 6 USBDP_DN3/PRT_DIS_P3 7
USBDM_DN4/PRT_DIS_M4 8 USBDP_DN4/PRT_DIS_P4 9
VDDA33 10 TEST 11 
PRTPWR1/BC_EN1 12 
OCS1# 13 
CRFILT 14 
VDD33 15 
PRTPWR2/BC_EN2 16 
OCS2# 17 
PRTPWR3/BC_EN3 18 
OCS3# 19 
PRTPWR4/BC_EN4 20 
OCS4# 21 
SDA/SMBDATA/NON_REM1 22 
VDD33 23 
SCL/SMBCLK/CFG_SEL0 24 
HS_IND/CFG_SEL1 25 
RESET# 26 
VBUS_DET 27 
SUSP_IND/LOCAL_PWR/NON_REM0 28 
VDDA33 29 
USBDM_UP 30 USBDP_UP 31 
XTALOUT 32 
XTALIN/CLKIN 33 
PLLFILT 34 
RBIAS 35 
VDDA33 36 
GND 37 
R20 
4K7R2F-GP 
4.7k ohm 
1/16W 
1% 
0402 
1 2C2 
SC1U16V3KX-5GP 
1uF 
16V 
10% 
0603 
X7R 
1 2
R36
4K7R2F-GP
4.7k ohm
1/16W
1%
0402
1 2
R25 
15KR2F-GP 
15k ohm 
1/16W 
1% 
0402 
NOPOP 
1 2
R24 
10KR2F-2-GP 
10k ohm 
1/16W 
1% 
0402 
1 2
C8 
SC1U16V3KX-5GP 
1uF 
16V 
10% 
0603 
X7R 
NOPOP 
1 2
R26 0 ohm 0402 12
C10 
SC1U16V2KX-7-GP 
1uF 
16V 
10% 
0402 
X6S 
1 2
L23 
BLM21PG300SN-2GP 
12
R53 
4K7R2F-GP 
4.7k ohm 
1/16W 
1% 
0402 
NOPOP 
1 2
C525 
SC1000P2KV6KX-GP-U 
1 2
D16 
PESD5V0S1BL-1-GP 
1 2
R19 
4K7R2F-GP 
NOPOP 
4.7k ohm 
1/16W 
1% 
0402 
1 2
C9 
SC1U16V2KX-7-GP 
1uF 
16V 
10% 
0402 
X6S 
1 2
C22 
SC1U16V3KX-5GP 
1uF 
16V 
10% 
0603 
X7R 
1 2
R30 
4K7R2F-GP 
4.7k ohm 
1/16W 
1% 
0402 
1 2
TP5 1
C19 
SC1U16V3KX-5GP
1uF 
16V 
10% 
0603 
X7R 
1 2
R32 
4K7R2F-GP 
4.7k ohm 
1/16W 
1% 
0402 
1 2
R35 
4K7R2F-GP 
4.7k ohm 
1/16W 
1% 
0402 
1 2
TP4 1
D19 
PESD5V0F1BL-GP 
12
L1 
DLW21HN900SQ2LGP-U 
NOPOP 
90Ohm@100MHz 
Isat=0.33A 
DCR=350mOhm 
Tmax=125C 
1
3
4
2
C1 
SCD1U16V2KX-3GP 
0.1uF 
16V 
10% 
0402 
X7R 
1 2
TP6 1



5
5
4
4
3
3
2
2
1
1
D D
C C
B B
A A
POWER/RESET BUTTON
1000PF 
2KV 
1206 
X7R 
1000PF 
2KV 
1206 
X7R 
FP_PWR_BTN_N_R FP_PWRBTN PWRBTN_OUT_N 
RSTBTN_OUT_N FP_RETBTN 
FP_RESET_RC_N 
FP_PWR_BTN_N 
SYS_RST_BTN_IN_N RST_BTN_GND 
PWR_BTN_GND 
P3V3_STBY 
P3V3_STBY 
P3V3_STBY 
P3V3_STBY 
P3V3_STBY 
PWRBTN_OUT_N 20 
RSTBTN_OUT_N 20 
Title 
Size Document Number Rev
Date: Sheet 
of 
Bryce Canyon_IO Module 2
POWER & RESET BUTTON 
A2 
15 47Friday, December 08, 2017 
Bryce Canyon_IO Module 
http://wiwynn.com 
8F,90,Sec,1. Xintai 5th Rd.,Xizhi Dist.,
New Taipei City 22102, Taiwan(R.O.C)
Title 
Size Document Number Rev
Date: Sheet 
of 
Bryce Canyon_IO Module 2
POWER & RESET BUTTON 
A2 
15 47Friday, December 08, 2017 
Bryce Canyon_IO Module 
http://wiwynn.com 
8F,90,Sec,1. Xintai 5th Rd.,Xizhi Dist.,
New Taipei City 22102, Taiwan(R.O.C)
Title 
Size Document Number Rev
Date: Sheet 
of 
Bryce Canyon_IO Module 2
POWER & RESET BUTTON 
A2 
15 47Friday, December 08, 2017 
Bryce Canyon_IO Module 
http://wiwynn.com 
8F,90,Sec,1. Xintai 5th Rd.,Xizhi Dist.,
New Taipei City 22102, Taiwan(R.O.C)
C27 
SCD1U16V2KX-3GP 
0.1uF 
16V 
10% 
0402 
X7R 
1 2
R51 33R2F-3-GP 
33 ohm 1/16W 1% 0402 
1 2
R48 
4K7R2F-GP 
4.7k ohm 
1/16W 
1% 
0402 
1 2
RST1 
SW-TACT-4P-210-GP 
12
4 3
R59 33R2F-3-GP 
33 ohm 1/16W 1% 0402 
1 2
R45 
1MR2F-GP 
1M ohm 
1/16W 
1% 
0402 
1 2
R58 33R2F-3-GP 
33 ohm 1/16W 1% 0402 
1 2
U5 
74LVC2G07GW-GP 
1
2
3 4
5
6
R65 
8K2R2J-3-GP 
8.2k ohm 
1/16W 
5% 
0402 
1 2
R47 
1MR2F-GP 
1M ohm 
1/16W 
1% 
0402 
1 2
C528 
SC1000P2KV6KX-GP-U 
1 2
C31 
SC1U16V3KX-5GP 
1uF 
16V 
10% 
0603 
X7R 
1 2
C529 
SC1000P2KV6KX-GP-U 
1 2
R49 
10KR2F-2-GP 
10k ohm 
1/16W 
1% 
0402 
1 2
D2 
PESD5V0X1UAB-GP 
K A
D3 
PESD5V0X1UAB-GP 
K A
R56 
10KR2F-2-GP 
10k ohm 
1/16W 
1% 
0402 
1 2
R52 33R2F-3-GP 
33 ohm 1/16W 1% 0402 
1 2
PWR1 
SW-TACT-4P-169-GP 
1 2
3 4
C26 
SC1U16V3KX-5GP 
1uF 
16V 
10% 
0603 
X7R 
1 2



5
5
4
4
3
3
2
2
1
1
D D
C C
B B
A A
ML_PWR_YELLOW_LED ML_PWR_YELLOW_LED_R 
ML_PWR_BLUE_LED ML_PWR_BLUE_LED_R 
ML_PWR_BLUE_LED_R 
BMC_ML_PWR_BLUE_LED_L BMC_ML_PWR_YELLOW_LED_R 
BMC_ML_PWR_BLUE_LED_R 
BMC_ML_PWR_BLUE_LED_L 
P3V3_STBY 
P5V_STBY 
P5V_STBY 
BMC_ML_PWR_YELLOW_LED 21 
BMC_ML_PWR_BLUE_LED 21 
Title 
Size Document Number Rev
Date: Sheet 
of 
Bryce Canyon_IO Module 2
RESERVE 
A3 
16 37 Thursday, August 03, 2017 
Bryce Canyon_IO Module 
http://www.wiwynn.com 
8F, 90, Sec.1, Xintai 5th Rd., Xizhi Dist.,
New Taipei City 22102, Taiwan (R.O.C.)
Title 
Size Document Number Rev
Date: Sheet 
of 
Bryce Canyon_IO Module 2
RESERVE 
A3 
16 37 Thursday, August 03, 2017 
Bryce Canyon_IO Module 
http://www.wiwynn.com 
8F, 90, Sec.1, Xintai 5th Rd., Xizhi Dist.,
New Taipei City 22102, Taiwan (R.O.C.)
Title 
Size Document Number Rev
Date: Sheet 
of 
Bryce Canyon_IO Module 2
RESERVE 
A3 
16 37 Thursday, August 03, 2017 
Bryce Canyon_IO Module 
http://www.wiwynn.com 
8F, 90, Sec.1, Xintai 5th Rd., Xizhi Dist.,
New Taipei City 22102, Taiwan (R.O.C.)
R745 120R3F-L-GP 
120 ohm 1/10W 1% 0603 
1 2
R817 130R3F-GP 
130 ohm 1/10W 1% 0603 
1 2
Q29 
2N7002K-1-GP 
G
D S
R614 0 ohm 0402 12
R609 0 ohm 0402 12 BLUE YELLOW 
LED7 
LED-BY-14-GP 
1
2
3
R746 
1KR2F-3-GP 
1k ohm 
1/16W 
1% 
0402 
1 2
Q1 
Q2 
D1 
G2 
S2 
G1 
S1 
D2 
Q28 
SSM6P39TU-GP 
1
2
3 4
5
6



5
5
4
4
3
3
2
2
1
1
D D
C C
B B
A A
470K ohm 
0402 
Q4_G 
FM_TPM_PRSNT_RST_N_C FM_TPM_PRSNT_RST_N 
VREF_2V2 
FM_TPM_PRSNT_RST_N_R 
FLA0_SPI_HOLD_N BMC_SPI_CLK_R 
FLA0_WP_N 
BMC_SPI_MOSI_R 
FLA0_SPI_RST 
FLA0_SPI_RST 
FLA0_WP_N 
FLA_CS_0_R 
FLA0_SPI_HOLD_N 
BMC_SPI_MISO_TPM 
BMC_SPI_CLK_R 
BMC_SPI_MOSI_R 
FLA_CS_0_R 
BMC_SPI_MISO_TPM 
FM_TPM_PRSNT_RST_N 
I2C_TPM_SCL 
I2C_TPM_SDA 
FLA0_SPI_RST 
FM_TPM_PRSNT_RST 
BMC_SELF_HW_RST_D 
BMC_CPU_DIS 
FLA_CS_0_R 
BMC_CPU_EN 
FLA0_WP_N 
WP_DISABLE 
WP_ENABLE 
P3V3_STBY P3V3_STBY 
P3V3_STBY 
P3V3_STBY 
P3V3_STBY 
P3V3_STBY 
P5V_STBY 
P3V3_STBY 
P3V3_STBY 
P3V3_STBY 
P3V3_STBY 
P3V3_STBY 
P3V3_STBY 
P3V3_STBY 
P3V3_STBY 
FM_BMC_RESET_N 22 
BMC_SELF_HW_RST 21 
BMC_TPM_RST_N 22 
FM_TPM_PRSNT_N 21 
FLA_CS_0_R 21 
BMC_SPI_MISO 21,24 
BMC_SPI_CLK_R 21 
BMC_SPI_MOSI_R 21 
I2C_TPM_SCL 20 
I2C_TPM_SDA 20
RST_BMC_EXTRST_N 21,22 
FLA0_WP_N 22 
Title 
Size Document Number Rev
Date: Sheet 
of 
Bryce Canyon_IO Module 2
POWER/ENCLOUSRE LED 
A3 
17 47 Friday, December 08, 2017 
Bryce Canyon_IO Module 
http://www.wiwynn.com 
8F, 90, Sec.1, Xintai 5th Rd., Xizhi Dist.,
New Taipei City 22102, Taiwan (R.O.C.)
Title 
Size Document Number Rev
Date: Sheet 
of 
Bryce Canyon_IO Module 2
POWER/ENCLOUSRE LED 
A3 
17 47 Friday, December 08, 2017 
Bryce Canyon_IO Module 
http://www.wiwynn.com 
8F, 90, Sec.1, Xintai 5th Rd., Xizhi Dist.,
New Taipei City 22102, Taiwan (R.O.C.)
Title 
Size Document Number Rev
Date: Sheet 
of 
Bryce Canyon_IO Module 2
POWER/ENCLOUSRE LED 
A3 
17 47 Friday, December 08, 2017 
Bryce Canyon_IO Module 
http://www.wiwynn.com 
8F, 90, Sec.1, Xintai 5th Rd., Xizhi Dist.,
New Taipei City 22102, Taiwan (R.O.C.)
Q2 
MMBT3904-3-GP 
C
B
E
SKT1 
SKT-SPI16P-GP-U 
1
2
3
4
5
6
7
8
16 
15 
14 
13 
12 
11 
10 
9
C34 
SCD1U16V2KX-3GP 
0.1uF 
16V 
10% 
0402 
X7R 
1 2
R77 
10KR2F-2-GP 
NOPOP 
10k ohm 
1/16W 
1% 
0402 
1 2
R71 
4K75R2F-1-GP 
4.75k ohm 
1/16W 
1% 
0402 
1 2
R788 0 ohm 0402 12
C38 
SCD1U16V2KX-3GP 
0.1uF 
16V 
10% 
0402 
X7R 
1 2
R789 0 ohm 0402 NOPOP 12
C36 
SCD1U16V2KX-3GP 
0.1uF 
16V 
10% 
0402 
X7R 
1 2
R781 0 ohm 0402 NOPOP 12
Q4 
2N7002K-1-GP 
G
D S
U9 
SN74LVC1G07DCKRG4-2-GP 
GND 3 A2 NC#1 1 VCC 5
Y 4
TPM1 
FCI-CONN11-2-GP 
1
2
3
4
5
6
7
8
9
10 
11 
G1 
G2 
NP1 
NP2 
R73 
4K75R2F-1-GP 
4.75k ohm 
1/16W 
1% 
0402 
1 2
+
-
U10 
LMV331IDCKRG4-GP 
1
3
4
5 2
R84 
4K7R2F-GP 
4.7k ohm 
1/16W 
1% 
0402 
1 2
R787 0 ohm 0402 12
R82 
10KR2F-2-GP 
10k ohm 
1/16W 
1% 
0402 
1 2
C49 
SCD1U16V2KX-3GP 
0.1uF 
16V 
10% 
0402 
X7R 
1 2
U11 
W25Q256FVFIQ-GP 
VCC 2
RESET# 3
NC#4 4
NC#5 5
NC#6 6
CS# 7
CLK 16 
NC#14 14 NC#13 13 NC#12 12 NC#11 11 
GND 10 
DI/IO0 15 
DO/IO1 8
WP#/IO2 9
HOLD#/IO3 1
R74 
0 ohm 0402 
1 2
R80 
100KR2F-L1-GP 
100k ohm 
1/16W 
1% 
0402 
1 2
R72 
10KR2F-2-GP 
10k ohm 
1/16W 
1% 
0402 
1 2
R85 
100KR2F-L1-GP 
100k ohm 
1/16W 
1% 
0402 
1 2
C35 SC1U16V2KX-7-GP 
1uF 16V 10% 0402 X6S 
1 2
R79 
470KR2F-GP 
1 2
R90 2K2R2J-2-GP 
2.2k ohm 1/16W 5% 0402 
1 2
R75 NOPOP 0 ohm 0402 1 2
R78 
10KR2F-2-GP 
10k ohm 
1/16W 
1% 
0402 
1 2
R76 
47KR2F-GP 
47k ohm 1/16W 1% 0402 
1 2
C50 
SCD1U16V2KX-3GP 
0.1uF 
16V 
10% 
0402 
X7R 
NOPOP 
1 2
C33 
SCD1U16V2KX-3GP 
0.1uF 
16V 
10% 
0402 
X7R 
1 2
R91 300R2F-GP 
300 ohm 1/16W 1% 0402 
1 2
R81 
4K75R2F-1-GP 
4.75k ohm 
1/16W 
1% 
0402 
1 2
C52 
SCD1U16V2KX-3GP 
0.1uF 
16V 
10% 
0402 
X7R 
NOPOP 
1 2Q3 
MMBT3904-3-GP 
C
B
E
R765 0 ohm 0402 NOPOP 12
R86 2K2R2J-2-GP 
2.2k ohm 1/16W 5% 0402 
1 2
D11 
BAT54WS-7-F-GP 
A K
R89 33D2R2F-GP 
33.2 ohm 1/16W 1% 0402 
1 2
R83 2K2R2J-2-GP 
2.2k ohm 1/16W 5% 0402 
1 2



5
5
4
4
3
3
2
2
1
1
D D
C C
B B
A A
BMC_TO_EXP_RESET_OUT_R 
PWRGD_P3V3_STBY 
SYS_RESET_N_OUT 
I2C_EXP_LOC_SCL_R 
I2C_EXP_LOC_SDA_R 
I2C_EXP_RMT_SCL_R 
I2C_EXP_RMT_SDA_R 
I2C_SCC_SCL_R 
I2C_SCC_SDA_R 
I2C_DPB_SCL_R 
I2C_DPB_SDA_R 
PWRGD_P3V3_STBY_N_R1 PWRGD_P3V3_STBY_N 
PWRGD_P3V3_STBY_N_R2 PWRGD_P3V3_STBY_N 
PWRGD_P3V3_STBY_N 
I2C_DPB_MISC_SCL_R 
I2C_DPB_MISC_SDA_R 
DPB_MISC_ALERT_OUT_R 
U104_EN 
I2C_BMC_COMP_SCL_R 
I2C_BMC_COMP_SCL_OUT 
I2C_BMC_COMP_SDA_R 
I2C_BMC_COMP_ALERT_N_R 
COMP_PWR_EN 
I2C_BMC_COMP_SDA_OUT 
I2C_COMP_ALERT_N 
COMP_TO_BMC_RESET_R 
P3V3_STBY 
P3V3_STBY 
P3V3_STBY 
P3V3_STBY 
P3V3_STBY 
P3V3_STBY 
P3V3_STBY 
P3V3_STBY 
P3V3_STBY 
BMC_TO_EXP_RESET_OUT 20 
BMC_TO_EXP_RESET_N 11 
SYS_RESET_N 11 
SYS_RESET_N_OUT 20 
I2C_EXP_LOC_SCL_OUT 20 I2C_EXP_LOC_SCL 11 
I2C_EXP_LOC_SDA_OUT 20 I2C_EXP_LOC_SDA 11 
I2C_EXP_RMT_SCL_OUT 20 I2C_EXP_RMT_SCL 11 
I2C_EXP_RMT_SDA_OUT 20 I2C_EXP_RMT_SDA 11 
I2C_SCC_SCL_OUT 20 I2C_SCC_SCL 11 
I2C_SCC_SDA 11 
I2C_DPB_SCL 11 
I2C_DPB_SDA 11 
I2C_SCC_SDA_OUT 20 
I2C_DPB_SCL_OUT 20 
I2C_DPB_SDA_OUT 20 
I2C_DPB_MISC_SCL 11 
I2C_DPB_MISC_SDA 11 
DPB_MISC_ALERT_OUT 21 
PWRGD_P3V3_STBY 29,30 
I2C_DPB_MISC_SCL_OUT 20 
I2C_DPB_MISC_SDA_OUT 20 
DPB_MISC_ALERT 11 
COMP_PWR_EN 11,18,22 
SYS_RST_EN 22 
I2C_BMC_COMP_SCL_OUT 20 
I2C_BMC_COMP_SCL 11 
COMP_PWR_EN 11,18,22 
I2C_COMP_ALERT_N 22 
I2C_BMC_COMP_ALERT_N 11 
I2C_BMC_COMP_SDA 11 
I2C_BMC_COMP_SDA_OUT 20 
COMP_TO_BMC_RESET 11 
COMP_TO_BMC_RESET_N_OUT 22
Title 
Size Document Number Rev
Date: Sheet 
of 
Bryce Canyon_IO Module 2
I2C SWITCH & BUFFER 
A3 
18 47 Friday, December 08, 2017 
Bryce Canyon_IO Module 
http://www.wiwynn.com 
8F, 90, Sec.1, Xintai 5th Rd., Xizhi Dist.,
New Taipei City 22102, Taiwan (R.O.C.)
Title 
Size Document Number Rev
Date: Sheet 
of 
Bryce Canyon_IO Module 2
I2C SWITCH & BUFFER 
A3 
18 47 Friday, December 08, 2017 
Bryce Canyon_IO Module 
http://www.wiwynn.com 
8F, 90, Sec.1, Xintai 5th Rd., Xizhi Dist.,
New Taipei City 22102, Taiwan (R.O.C.)
Title 
Size Document Number Rev
Date: Sheet 
of 
Bryce Canyon_IO Module 2
I2C SWITCH & BUFFER 
A3 
18 47 Friday, December 08, 2017 
Bryce Canyon_IO Module 
http://www.wiwynn.com 
8F, 90, Sec.1, Xintai 5th Rd., Xizhi Dist.,
New Taipei City 22102, Taiwan (R.O.C.)
R93 
NOPOP 
0 ohm 
0402 
12
C136 
SCD1U16V2KX-3GP 
0.1uF 
16V 10% 0402 
X7R 
1 2
R132 0 ohm 0402 12
R736 0 ohm 0402 12
R717 0 ohm 0402 12
C41 
SCD1U16V2KX-3GP 
0.1uF 
16V 10% 0402 
X7R 
1 2
R732 0 ohm 0402 12
U103 
SNLVC1G126DCKR-GP 
OE 1
A2
GND 3 Y 4
VCC 5
R129 0 ohm 0402 12
R329 0 ohm 0402 12
U104 
SNLVC1G126DCKR-GP 
OE 1
A2
GND 3 Y 4
VCC 5
C44 
SCD1U16V2KX-3GP 
0.1uF 
16V 10% 0402 
X7R 
1 2
U15 
NX3L1G66GW-GP 
Y1
Z2
GND 3 E 4
VCC 5
R617 0 ohm 0402 12
C508 
SCD1U16V2KX-3GP 
0.1uF 
16V 10% 0402 
X7R 
1 2
U107 
SN74CBTLV3245APWR-GP 
NC#1 1
A1 2
A2 3
A3 4
A4 5
A5 6
A6 7
A7 8
A8 9
GND 10 
B8 11 B7 12 B6 13 B5 14 B4 15 B3 16 B2 17 B1 18 
OE# 19 VCC 20 
C502 
SCD1U16V2KX-3GP 
0.1uF 
16V 10% 0402 
X7R 
1 2
R734 0 ohm 0402 NOPOP 12
U16 
NX3L1G66GW-GP 
Y1
Z2
GND 3 E 4
VCC 5
U12 
NX3L1G66GW-GP 
Y1
Z2
GND 3 E 4
VCC 5
R130 0 ohm 0402 12
R92 0 ohm 0402 12
R96 0 ohm 0402 12
R724 0 ohm 0402 12
R720 0 ohm 0402 12
R100 0 ohm 0402 12
R124 0 ohm 0402 12
R127 0 ohm 0402 12
R718 0 ohm 0402 12
C135 
SCD1U16V2KX-3GP 
0.1uF 
16V 10% 0402 
X7R 
1 2
U102 
SN74LVC1G14DCKR-GP 
NC#1 1
A2
GND 3 Y 4
VCC 5
R123 0 ohm 0402 12
R97 
NOPOP 
0 ohm 
0402 
12
C39 
SCD1U16V2KX-3GP 
0.1uF 
16V 10% 0402 
X7R 
1 2
R596 
4K7R2F-GP 
4.7k ohm 
1/16W 
1% 
0402 
1 2
C141 
SCD1U16V2KX-3GP 
0.1uF 
16V 10% 0402 
X7R 
1 2
U105 
SN74CBTLV3245APWR-GP 
NC#1 1
A1 2
A2 3
A3 4
A4 5
A5 6
A6 7
A7 8
A8 9
GND 10 
B8 11 B7 12 B6 13 B5 14 B4 15 B3 16 B2 17 B1 18 
OE# 19 VCC 20 
C37 
SCD1U16V2KX-3GP 
0.1uF 
16V 10% 0402 
X7R 
1 2
U106 
SNLVC1G14DBVR-GP 
NC#1 1
A2
GND 3 Y 4
VCC 5
R131 0 ohm 0402 12
R101 
NOPOP 
0 ohm 
0402 
12
R128 0 ohm 0402 12



5
5
4
4
3
3
2
2
1
1
D D
C C
B B
A A
EEPROM_A2 
EEPROM_WP 
EEPROM_A0 
EEPROM_A1 
I2C_IOM_SCL 
I2C_IOM_SDA 
TEMP_3_A0 
TEMP_3_ALERT 
TEMP_3_SDA 
TEMP_3_A1 
TEMP_3_A2 
TEMP_3_SCL 
P3V3_STBY P3V3_STBY 
P3V3_STBY P3V3_STBY 
I2C_IOM_SDA 19,20,27 
I2C_IOM_SCL 19,20,27 
I2C_IOM_SCL 19,20,27 
I2C_IOM_SDA 19,20,27 
Title 
Size Document Number Rev
Date: Sheet 
of 
Bryce Canyon_IO Module 2
I2C DEVICES 
A2 
19 47 Friday, December 08, 2017 
Bryce Canyon_IO Module 
http://www.wiwynn.com 
8F, 90, Sec.1, Xintai 5th Rd., Xizhi Dist.,
New Taipei City 22102, Taiwan (R.O.C.)
Title 
Size Document Number Rev
Date: Sheet 
of 
Bryce Canyon_IO Module 2
I2C DEVICES 
A2 
19 47 Friday, December 08, 2017 
Bryce Canyon_IO Module 
http://www.wiwynn.com 
8F, 90, Sec.1, Xintai 5th Rd., Xizhi Dist.,
New Taipei City 22102, Taiwan (R.O.C.)
Title 
Size Document Number Rev
Date: Sheet 
of 
Bryce Canyon_IO Module 2
I2C DEVICES 
A2 
19 47 Friday, December 08, 2017 
Bryce Canyon_IO Module 
http://www.wiwynn.com 
8F, 90, Sec.1, Xintai 5th Rd., Xizhi Dist.,
New Taipei City 22102, Taiwan (R.O.C.)
R342 0 ohm 0402 12
C51 
SCD1U16V2KX-3GP 
0.1uF 
16V 
10% 
0402 
X7R 
1 2
R139 
8K2R2J-3-GP 
8.2k ohm 
1/16W 
5% 
0402 
1 2
R344 0 ohm 0402 12
R282 
4K7R2F-GP 
NOPOP 
4.7k ohm 
1/16W 
1% 
0402 
1 2
R285 
4K7R2F-GP 
NOPOP 
4.7k ohm 
1/16W 
1% 
0402 
1 2
R133 
8K2R2J-3-GP 
NOPOP 
8.2k ohm 
1/16W 
5% 
0402 
1 2
C506 
SCD1U16V2KX-3GP 
0.1uF 
16V 
10% 
0402 
X7R 
1 2
U26 
24LC64-I-SN-GP 
A0 1
A1 2
A2 3
VSS 4 SDA 5SCL 6WP 7VCC 8
R337 
4K7R2F-GP 
4.7k ohm 
1/16W 
1% 
0402 
1 2
R339 
4K7R2F-GP 
4.7k ohm 
1/16W 
1% 
0402 
1 2
U27 
TMP75AIDGKR-GP 
SDA 1
SCL 2
ALERT 3
GND 4 A2 5A1 6A0 7V+ 8
R138 
8K2R2J-3-GP 
8.2k ohm 
1/16W 
5% 
0402 
1 2
R347 
4K7R2F-GP 
NOPOP 
4.7k ohm 
1/16W 
1% 
0402 
1 2
R341 
4K7R2F-GP 
4.7k ohm 
1/16W 
1% 
0402 
1 2
R136 
8K2R2J-3-GP 
8.2k ohm 
1/16W 
5% 
0402 
1 2
TP19 
1
R137 
8K2R2J-3-GP 
8.2k ohm 
1/16W 
5% 
0402 
1 2
R135 
8K2R2J-3-GP 
NOPOP 
8.2k ohm 
1/16W 
5% 
0402 
1 2
R134 
8K2R2J-3-GP 
NOPOP 
8.2k ohm 
1/16W 
5% 
0402 
1 2



5
5
4
4
3
3
2
2
1
1
D D
C C
B B
A A
I2C_BMC_COMP_SDA_OUT 
I2C_BMC_COMP_SCL_OUT 
DDR_VREF 
I2C_DEBUG_SDA_L 
I2C_DEBUG_SCL_L 
I2C_M2_1_SCL 
I2C_M2_1_SDA 
I2C_MEZZ_OOB_SCL 
I2C_MEZZ_OOB_SDA 
I2C_EXP_LOC_SCL_OUT 
I2C_EXP_LOC_SDA_OUT 
I2C_EXP_RMT_SCL_OUT 
I2C_EXP_RMT_SDA_OUT 
I2C_IOM_SCL 
I2C_IOM_SDA 
I2C_TPM_SDA 
I2C_TPM_SCL 
I2C_MEZZ_FRU_SENSOR_SDA 
I2C_MEZZ_FRU_SENSOR_SCL 
I2C_SCC_SCL_OUT 
I2C_SCC_SDA_OUT 
I2C_DPB_SCL_OUT 
I2C_DPB_SDA_OUT 
I2C_DPB_MISC_SCL_OUT 
I2C_DPB_MISC_SDA_OUT 
I2C_M2_2_SCL 
I2C_M2_2_SDA 
PD_PERST_N 
BMC_PEREXT 
TP_BMC0_LPC_LAD0 
TP_BMC0_LPC_LAD1 
TP_BMC0_LPC_LAD2 
TP_BMC0_LPC_LAD3 
BMC_SMB2_CLK 
BMC_SMB2_DAT 
BMC_SMB3_CLK 
BMC_SMB3_DAT 
BMC_SMB4_CLK 
BMC_SMB4_DAT 
BMC_SMB1_CLK 
BMC_SMB1_DAT 
BMC_SMB9_DAT 
BMC_SMB6_DAT 
BMC_SMB6_CLK 
BMC_SMB7_DAT 
BMC_SMB7_CLK 
BMC_SMB8_DAT 
BMC_SMB8_CLK I2C_M2_1_SCL 
I2C_M2_1_SDA 
BMC_SMB9_CLK I2C_M2_2_SCL 
I2C_M2_2_SDA 
BMC_SMB13_DAT 
BMC_SMB13_CLK 
BMC_SMB11_DAT 
BMC_SMB11_CLK 
BMC_SMB10_DAT 
BMC_SMB10_CLK 
BMC_SMB12_DAT 
BMC_SMB12_CLK 
COMP_PWR_BTN_R_N 
PWRBTN_OUT_N_R 
BMC_SMB14_DAT 
BMC_SMB14_CLK 
LPC_CPU_FRAME_N 
LPC_CPU_CLKOUT0 
IRQ_CPU_SERIAL 
DDR_VREF 
MIOZ 
MEMCK_P 
MEMCK_N 
MEMCKE 
MEMODT 
MEMCSN 
MEMRASN 
MEMCASN 
MEMWEN 
MEMBA_0 
MEMBA_1 
MEMBG_0 
MEMA_13 
DDR4_ACT 
MEMA_10 
MEMA_11 
MEMA_12 
MEMA_0 
MEMA_1 
MEMA_2 
MEMA_3 
MEMA_4 
MEMA_5 
MEMA_6 
MEMA_7 
MEMA_8 
MEMA_9 
MEMDM_0 
MEMDM_1 
MEMDQ_5 
MEMDQ_6 
MEMDQ_7 
MEMDQ_8 
MEMDQ_9 
MEMDQ_10 
MEMDQ_11 
MEMDQ_12 
MEMDQ_13 
MEMDQ_14 
MEMDQ_15 
MEMDQ_0 
MEMDQ_1 
MEMDQ_2 
MEMDQ_3 
MEMDQ_4 
MEMDQS_N1 
MEMDQS_P0 
MEMDQS_N0 
DDR4_ALERT 
DDR4_RST_N 
PD_ZQ 
DDR_VREF 
MEMDQ_0 
MEMDQ_1 
MEMDQ_2 
MEMDQ_3 
MEMDQ_4 
MEMDQ_5 
MEMDQ_6 
MEMDQ_7 
MEMDQ_8 
MEMDQ_9 
MEMDQ_10 
MEMDQ_11 
MEMDQ_12 
MEMDQ_13 
MEMDQ_14 
MEMDQ_15 
MEMDQS_P1 
MEMDQS_N1 
MEMDQS_P0 
MEMDQS_N0 
MEMDM_0 
MEMDM_1 
MEMBG_0 
MEMBA_0 
MEMBA_1 
MEMA_11 
MEMA_10 
MEMA_12 
MEMA_1 
MEMA_0 
MEMA_3 
MEMA_2 
MEMA_6 
MEMA_5 
MEMA_4 
MEMA_8 
MEMA_7 
MEMA_9 
MEMA_13 
MEMCK_P 
MEMCK_N 
MEMCKE 
MEMRASN 
MEMCASN 
MEMWEN 
MEMCSN 
DDR4_ACT 
MEM_PAR 
DDR4_ALERT 
MEMODT 
DDR4_RST_N 
DDR4_RST_N 
MEMCKE 
MEMODT 
DDR4_ALERT 
MEMCSN 
MEMBG_0 
DDR4_ACT 
MEMRASN 
MEMCASN 
MEMWEN 
MEMBA_0 
MEMBA_1 
MEMA_0 
MEMA_1 
MEMA_2 
MEMA_3 
MEMA_4 
MEMA_5 
MEMA_6 
MEMA_7 
MEMA_8 
MEMA_9 
MEMA_10 
MEMA_11 
MEMA_12 
MEMA_13 
LPCRST0_N 
MEMCK_P 
MEMCK_N 
MEMCK_TER 
SYS_PWR_LED 
SYS_PWR_LED 
SYS_PWR_LED 
BMC_TO_EXP_RESET_OUT 
BMC_TO_EXP_RESET_OUT 
DB_PRSNT_BMC_N 
BMC_SMB5_CLK 
BMC_SMB5_DAT 
SYS_RESET_N_OUT_R 
RSTBTN_OUT_N_R 
SYS_RESET_N_OUT 
COMP_PWR_BTN_N 
USB_OCS_N1 
TP_BMC_GPIOA0 
TP_BMC_GPIOA0 
TP_M2_1_ALERT# 
TP_M2_2_ALERT# 
P1V2_STBY 
P3V3_STBY 
P1V2_STBY 
P1V2_STBY 
P1V2_STBY 
P1V2_STBY 
P2V5_STBY 
P1V2_STBY 
P1V2_STBY 
P2V5_STBY 
P3V3_STBY P3V3_STBY 
P1V2_STBY 
P3V3_STBY 
I2C_IOC_SDA 44 
I2C_IOC_SCL 44 
I2C_SCC_SCL_OUT 18 
I2C_SCC_SDA_OUT 18 
I2C_BMC_COMP_SDA_OUT 18 
I2C_BMC_COMP_SCL_OUT 18 
I2C_IOM_SDA 19,27 
I2C_IOM_SCL 19,27 
I2C_DPB_MISC_SCL_OUT 18 
I2C_DPB_MISC_SDA_OUT 18 
I2C_DPB_SDA_OUT 18 
I2C_DPB_SCL_OUT 18 
I2C_MEZZ_FRU_SENSOR_SCL 12 
I2C_MEZZ_FRU_SENSOR_SDA 12 
I2C_EXP_RMT_SCL_OUT 18 
I2C_EXP_RMT_SDA_OUT 18 
I2C_EXP_LOC_SCL_OUT 18 
I2C_EXP_LOC_SDA_OUT 18 
I2C_DEBUG_SCL_L 26 
I2C_DEBUG_SDA_L 26 
COMP_PWR_BTN_N 11 
PWRBTN_OUT_N 15 
I2C_TPM_SCL 17 
I2C_TPM_SDA 17 
SYS_PWR_LED 11 
BMC_TO_EXP_RESET_OUT 18 DB_PRSNT_BMC_N 26 
I2C_MEZZ_OOB_SDA 12 
I2C_MEZZ_OOB_SCL 12 
RSTBTN_OUT_N 15 
SYS_RESET_N_OUT 18 
USB_OCS_N1 14 
Title 
Size Document Number Rev
Date: Sheet 
of 
Bryce Canyon_IO Module 2
AST2500 I2C DDR LPC 
A2 
20 47Friday, December 08, 2017 
Bryce Canyon_IO Module 
http://www.wiwynn.com 
8F, 90, Sec.1, Xintai 5th Rd., Xizhi Dist.,
New Taipei City 22102, Taiwan (R.O.C.)
Title 
Size Document Number Rev
Date: Sheet 
of 
Bryce Canyon_IO Module 2
AST2500 I2C DDR LPC 
A2 
20 47Friday, December 08, 2017 
Bryce Canyon_IO Module 
http://www.wiwynn.com 
8F, 90, Sec.1, Xintai 5th Rd., Xizhi Dist.,
New Taipei City 22102, Taiwan (R.O.C.)
Title 
Size Document Number Rev
Date: Sheet 
of 
Bryce Canyon_IO Module 2
AST2500 I2C DDR LPC 
A2 
20 47Friday, December 08, 2017 
Bryce Canyon_IO Module 
http://www.wiwynn.com 
8F, 90, Sec.1, Xintai 5th Rd., Xizhi Dist.,
New Taipei City 22102, Taiwan (R.O.C.)
R253 120 ohm 0402 1 2
R196 2.2k ohm 0402 1 2
R248 120 ohm 0402 1 2
R216 120 ohm 0402 1 2
R204 2.2k ohm 0402 1 2
R178 0 ohm 0402 12
R143 
1KR2D-1-GP 
1 2
R242 120 ohm 0402 1 2 R243 120 ohm 0402 1 2
R176 0 ohm 0402 12
R208 NOPOP 120 ohm 0402 1 2
R181 2.2k ohm 0402 1 2
R185 2.2k ohm 0402 1 2
R278 0 ohm 0402 12
U28 
H5AN4G6NAFR-TFC-GP 
VPP B1 
VDD B3 
VDD B9 
VDD D1 
VDD G7 
VDD J1 
VDD J9 
VDD L1 
VDD L9 
VDD R1 
VDD T9 
VDDQ A1 
VDDQ A9 
VDDQ C1 
VDDQ D9 
VDDQ F2 
VDDQ F8 
VDDQ G1 
VDDQ G9 
VDDQ J2 
VDDQ J8 
DQU4 C2 
DQU5 C8 
DQU6 D3 
DQU7 D7 
DQU0 A3 
DQU1 B8 
DQU2 C3 
DQU3 C7 
DQL1 F7 DQL0 G2 
DQL4 H2 
DQL2 H3 
DQL3 H7 
DQL5 H8 
DQL6 J3 
DQL7 J7 
A0 P3 
A1 P7 
A2 R3 
A3 N7 
A4 N3 
A5 P8 
A6 P2 
A7 R8 
A8 R2 
A9 R7 
A10/AP M3 
A11 T2 
A12/BC# M7 
A13 T8 
WE#/A14 L2 
CAS#/A15 M8 
RAS#/A16 L8 
VREFCA M1 
ZQ F9 
CKE K2 
ODT K3 
BG0 M2 
TEN N9 
PAR T3 
NC#T7 T7 
CK_T K7 
CK_C K8 
VPP R9 ACT# L3 
CS# L7 
RESET# P1 
ALERT# P9 
VSS B2 
VSS E1 
VSS E9 
VSS G8 
VSS K1 
VSS K9 
VSS M9 
VSS N1 
VSS T1 
VSSQ A2 
VSSQ A8 
VSSQ C9 
VSSQ D2 
VSSQ D8 
VSSQ E3 
VSSQ E8 
VSSQ F1 
VSSQ H1 
VSSQ H9 DQSU_C A7 
DQSU_T B7 
DQSL_C F3 
DQSL_T G3 
DMU#/DBIU# E2 
DML#/DBIL# E7 
BA0 N2 
BA1 N8 
C62 
SC1U16V3KX-5GP 
1uF 
16V 
10% 
0603 
X7R 
1 2
R156 0 ohm 0402 12
R165 0 ohm 0402 12
TP10 1
R199 1k ohm 0402 1 2
R235 120 ohm 0402 1 2
R210 120 ohm 0402 1 2
R174 0 ohm 0402 12
R209 120 ohm 0402 1 2
R191 2.2k ohm 0402 1 2
R232 120 ohm 0402 1 2
R207 NOPOP 120 ohm 0402 1 2
R229 120 ohm 0402 1 2
R784 
10KR2F-2-GP 
10k ohm 
1/16W 
1% 
0402 
1 2
R172 0 ohm 0402 12
R257 120 ohm 0402 1 2
R161 0 ohm 0402 12
R221 120 ohm 0402 1 2
C73 
SCD1U16V2KX-3GP 
0.1uF 
16V 
10% 
0402 
X7R 
12
R214 2.7k ohm 0402 1 2
PCI-Express 
DDR3/DDR4 
LPC 
ESPI 
I2C 
SD/SDIO 
GPIO 
1 OF 4 U2A 
AST2500A2-GP-GP-U 
PEREXT K20 
PERST# L20 
PEREFCLKN K22 PEREFCLKP K21 
PERXN M22 PERXP M21 
PETXN L22 PETXP L21 
MVREF T9 
MIOZ W11 
MRESET# AB17 
MALERT# U16 
MDQ0 U10 
MDQ1 W10 
MDQ2 Y10 
MDQ3 AA10 
MDQ4 U9 
MDQ5 Y9 
MDQ6 W9 
MDQ7 V9 
MDQ8 AA8 
MDQ9 Y8 
MDQ10 Y7 
MDQ11 W8 
MDQ12 AA6 
MDQ13 W7 
MDQ14 V7 
MDQ15 U7 
MDQS0 AB9 
MDQS1 AB7 
MDQS0# AB10 
MDQS1# AB6 
MCK AB11 
MCK# AB12 
MCKE Y11 
MODT V11 
MCS# AA12 
MRAS# W12 
MCAS# AB13 
MWE# Y12 
MBA0 U12 
MBA1 Y13 
MBA2_MBG0 W13 
MA0 V13 
MA1 AB14 
MA2 W14 
MA3 U14 
MA4 W15 
MA5 V15 
MA6 AB16 
MA7 AA16 
MA8 W16 
MA9 Y16 
MA10 U13 
MA11 AA14 
MA12 Y14 
MA13 AB15 
MA14_MACT# Y15 
MA15 U15 
MDM0 U8 
MDM1 AB8 
GPIOAC4_ESPICK_LCLK C22 
GPIOAC5_ESPICS#_LFRAME# F21 
GPIOAC6_ESPIALT#_LSIRQ# F22 
GPIOAC7_ESPIRST#_LPCRST# G22 
GPIOAC0_ESPID0_LAD0 G21 
GPIOAC1_ESPID1_LAD1 G20 
GPIOAC2_ESPID2_LAD2 D22 
GPIOAC3_ESPID3_LAD3 E22 
GPIOB4_USBCKI J20 
GPIOB5_LPCPD#_LPCSMI# H21 
GPIOB6_LPCPME# H22 
GPIOB7 H20 
GPIOB0 K19 
GPIOB1 L19 
GPIOB2 L18 
GPIOB3 K18 
GPIOY4_SCL1 M18 
GPIOY5_SDA1 M19 
GPIOY6_SCL2 M20 
GPIOY7_SDA2 P20 
GPIOQ0_SCL3 A11 
GPIOQ1_SDA3 A10 
GPIOQ2_SCL4 A9 
GPIOQ3_SDA4 B9 
GPIOK0_SCL5 L3 
GPIOK1_SDA5 L4 
GPIOK2_SCL6 L1 
GPIOK3_SDA6 N2 
GPIOK4_SCL7 N1 
GPIOK5_SDA7 P1 
GPIOK6_SCL8 P2 
GPIOK7_SDA8 R1 
GPIOA4_TIMER5_SCL9 C14 
GPIOA5_TIMER6_SDA9 A13 
GPIOC0_SD1CLK_SCL10 C12 
GPIOC1_SD1CMD_SDA10 A12 
GPIOC2_SD1DAT0_SCL11 B12 
GPIOC3_SD1DAT1_SDA11 D9 
GPIOC4_SD1DAT2_SCL12 D10 
GPIOC5_SD1DAT3_SDA12 E12 
GPIOC6_SD1CD#_SCL13 C11 
GPIOC7_SD1WP#_SDA13 B11 
GPIOD0_SD2CLK F19 
GPIOD1_SD2CMD E21 
GPIOD2_SD2DAT0 F20 
GPIOD3_SD2DAT1 D20 
GPIOD4_SD2DAT2 D21 
GPIOD5_SD2DAT3 E20 
GPIOD6_SD2CD# G18 
GPIOD7_SD2WP# C21 
GPIOQ4_SCL14 N21 
GPIOQ5_SDA14 N22 
GPIOQ6_OSCCLK B10 
GPIOQ7_PEWAKE# N20 
GPIOA0_MAC1LINK B14 
GPIOA1_MAC2LINK D14 
GPIOA2_TIMER3_SPI1CS1# D13 
GPIOA3_TIMER4 E13 
R157 0 ohm 0402 12
R281 0 ohm 0402 12
R247 120 ohm 0402 1 2
TP9 1
R186 2.2k ohm 0402 1 2
R152 0 ohm 0402 12
R222 120 ohm 0402 1 2
R182 2.2k ohm 0402 1 2
R258 120 ohm 0402 1 2
R170 0 ohm 0402 12
C68 
SCD1U16V2KX-3GP 
0.1uF 
16V 
10% 
0402 
X7R 
12
R236 120 ohm 0402 1 2
R219 240R2F-1-GP 
240 ohm 1/16W 1% 0402 
1 2
C57 
SC10U6D3V5KX-4GP 
10uF 
6.3V 
10% 
0805 
X7R 
12
R215 120 ohm 0402 1 2
R166 0 ohm 0402 12
R252 120 ohm 0402 1 2
C55 SCD1U16V2KX-3GP 
0.1uF 16V 10% 0402X7R 
1 2
R192 2.2k ohm 0402 1 2
C54 
SC1U16V3KX-5GP 
1uF 
16V 
10% 
0603 
X7R 
1 2
R246 120 ohm 0402 1 2
C64 
SC1U16V3KX-5GP 
1uF 
16V 
10% 
0603 
X7R 
1 2
R190 0402 499 ohm 1 2
R226 120 ohm 0402 1 2
R141 
1KR2D-1-GP 
1 2
R206 60D4R2F-GP 
60.4 ohm 1/16W 1% 0402 
1 2
R261 120 ohm 0402 1 2
R224 
4K7R2F-GP 
4.7k ohm 
1/16W 
1% 
0402 
NOPOP 
12
R151 0 ohm 0402 12
R162 0 ohm 0402 12
TP12 1
R187 2.2k ohm 0402 1 2
C66 SCD1U16V2KX-3GP 
0.1uF 16V 10% 0402 X7R 
1 2
C59 
SC1U16V3KX-5GP 
1uF 
16V 
10% 
0603 
X7R 
1 2
R183 2.2k ohm 0402 1 2
C65 
SC1U16V3KX-5GP 
1uF 
16V 
10% 
0603 
X7R 
1 2
R142 200R2F-L-GP 
200 ohm 1/16W 1% 0402 
1 2
R148 100k ohm 0402 12
TP15 1
R251 120 ohm 0402 1 2
R240 120 ohm 0402 1 2
R169 0 ohm 0402 12
R233 120 ohm 0402 1 2
C60 
SC1U16V3KX-5GP 
1uF 
16V 
10% 
0603 
X7R 
1 2
R158 0 ohm 0402 12
R785 
10KR2F-2-GP 
10k ohm 
1/16W 
1% 
0402 
NOPOP 
1 2
R241 120 ohm 0402 1 2
C56 
SC1U16V3KX-5GP 
1uF 
16V 
10% 
0603 
X7R 
1 2
R201 2.2k ohm 0402 1 2
R193 20k ohm 0402 12
R153 0 ohm 0402 12
R140 100KR2F-L1-GP 
100k ohm 1/16W 1% 0402 
1 2
R230 120 ohm 0402 1 2
R155 0 ohm 0402 12
R167 0 ohm 0402 12R716 
10KR2F-2-GP 
10k ohm 
1/16W 
1% 
0402 
NOPOP 
1 2
R200 2.2k ohm 0402 1 2
R273 4.7k ohm 0402 NOPOP 1 2
R271 4.7k ohm 0402 1 2
R177 0 ohm 0402 12
R227 120 ohm 0402 1 2
R175 0 ohm 0402 12
R149 100k ohm 0402 12
R218 120 ohm 0402 1 2
R220 120 ohm 0402 1 2
C58 
SC1U16V3KX-5GP 
1uF 
16V 
10% 
0603 
X7R 
1 2
R256 120 ohm 0402 1 2
TP16 1
C67 
SCD1U16V2KX-3GP 
0.1uF 
16V 
10% 
0402 
X7R 
12 C70 
SCD1U16V2KX-3GP 
0.1uF 
16V 
10% 
0402 
X7R 
12
R188 2.2k ohm 0402 1 2
TP14 1
R255 120 ohm 0402 1 2
C71 
SCD1U16V2KX-3GP 
0.1uF 
16V 
10% 
0402 
X7R 
12
TP11 1
R607 0 ohm 0402 12
TP20 1
R202 2.2k ohm 0402 1 2
R173 0 ohm 0402 12
R245 120 ohm 0402 1 2
R211 120 ohm 0402 1 2
R163 0 ohm 0402 12
R250 120 ohm 0402 1 2
R171 0 ohm 0402 12
R279 0 ohm 0402 12
R212 120 ohm 0402 1 2
R159 0 ohm 0402 12
R244 120 ohm 0402 1 2
R234 120 ohm 0402 1 2
R739 
10KR2F-2-GP 
10k ohm 
1/16W 
1% 
0402 
NOPOP 
1 2
R179 2.2k ohm 0402 1 2
R197 2.2k ohm 0402 1 2
R154 0 ohm 0402 12
R259 120 ohm 0402 1 2
R237 120 ohm 0402 1 2
TP21 1
R223 120 ohm 0402 1 2
R168 0 ohm 0402 12
R145 240R2F-1-GP 
240 ohm 1/16W 1% 0402 
1 2
R203 2.2k ohm 0402 1 2
R164 0 ohm 0402 12
TP13 1
R231 120 ohm 0402 1 2
R195 2.2k ohm 0402 1 2
C72 
SCD1U16V2KX-3GP 
0.1uF 
16V 
10% 
0402 
X7R 
12
R249 120 ohm 0402 1 2
R189 0402 499 ohm 1 2
R198 1k ohm 0402 1 2
R180 2.2k ohm 0402 1 2
R225 120 ohm 0402 1 2
R260 120 ohm 0402 1 2
R213 NOPOP 120 ohm 0402 1 2
C61 
SC1U16V3KX-5GP 
1uF 
16V 
10% 
0603 
X7R 
1 2
C63 
SC4D7U25V5KX-1-GP 
4.7uF 
25V 
10% 
0805 
X7R 
1 2
R160 0 ohm 0402 12
R238 120 ohm 0402 1 2
R147 100k ohm 0402 12
R184 2.2k ohm 0402 1 2
R146 100k ohm 0402 12
R205 60D4R2F-GP 
60.4 ohm 1/16W 1% 0402 
1 2
R144 
4K7R2F-GP 
NOPOP 
4.7k ohm 
1/16W 
1% 
0402 
12
R272 NOPOP 4.7k ohm 0402 1 2
R194 20k ohm 0402 12
R228 120 ohm 0402 1 2
C53 
SCD01U25V2KX-3GP 
0.01uF 
25V 
10% 
0402 
X7R 
1 2
R217 120 ohm 0402 1 2
R239 
0R2J-2-GP 
0 ohm 
1/16W 
5% 
0402 
1 2
R783 
10KR2F-2-GP 
10k ohm 
1/16W 
1% 
0402 
1 2
R254 120 ohm 0402 1 2
C69 
SCD1U16V2KX-3GP 
0.1uF 
16V 
10% 
0402 
X7R 
12



5
5
4
4
3
3
2
2
1
1
D D
C C
B B
A A
PU_IBMC_BT_HOLD_N 
FLA_CS_1_R 
BMC_SPI_CLK_R 
FLA1_WP_N 
BMC_SPI_MOSI_R 
BMC_SPI_MOSI_R 
FLA_CS_1_R 
BMC_SPI_CLK_R 
FLA1_WP_N 
PU_IBMC_BT_HOLD_N 
FM_OSC_50M_EN 
BMC_SPI_MISO_R 
BMC_SPI_MISO_R BMC_SPI_MISO 
FLA1_SPI_RST 
TP_BMC_GPIOR4 
TP_BMC_GPIOR5 
TP_BMC_GPIOR3 
TP_BMC_GPIOR2 
TP_BMC_GPIOR1 
FLA_CS_0 
FLA_CS_1 
BMC_SPI_CLK 
BMC_SPI_MOSI 
BMC_SPI_MISO 
BMC_GPIOY0 
BMC_GPIOY1 
BMC_GPIOY2 
BMC_GPIOY3 
MAC1_TXD2 
RMII_BMC_MDC_R 
RMII_BMC_MDIO_R 
BMC_RGMII_C2_C3_D1_D2_E6 
CLK_50M_BMC_NCSI 
NCSI_RXD0 
NCSI_RXD1 
NCSI_RX_ER 
NCSI_RCSDV 
BMC_RGMII_A4_D3 
UART_BMC_R_RX 
UART_BMC_R_TX 
BMC_SPI_MOSI_R 
BMC_SPI_CLK_R 
BMC_SPI_MOSI 
BMC_SPI_CLK 
FLA_CS_0 FLA_CS_0_R 
FLA_CS_1 FLA_CS_1_R 
SCC_LOC_FULLPWR_EN 
UART_BMC_COMP_IN_RX 
UART_COMP_OUT_TX 
TP_BMC_GPIOT6 
TP_BMC_GPIOA6 
TP_BMC_GPIOA7 
TP_BMC_GPIOT0 
NCSI_TXEN 
BMC_GPIOZ4 
BMC_GPIOZ5 
BMC_GPIOZ6 
BMC_GPIOZ7 
BMC_GPIOY0 
BMC_GPIOY1 
BMC_GPIOY2 
BMC_GPIOY3 
BMC_GPIOS4 
BMC_GPIOS5 
BMC_GPIOS6 
BMC_GPIOS7 
MAC1_TXD3 
MAC2_TXD0 
MAC2_TXD1 
MAC2_TXD2 
MAC2_TXD3 
MAC2_TXCTL 
I2C_MEZZ_ALERT_N 
EXP_SPARE_0_R 
EXP_SPARE_1_R 
DPB_MISC_ALERT_O_R 
P12V_A_PGOOD_R 
SCC_PWR_EN_R 
SCC_RMT_FULLPWR_EN 
IOM_LOC_INS_N 
UART_BMC_COMP_IN_RX 
UART_COMP_OUT_TX_R 
TP_BMC_GPIOL0 
TP_BMC_GPIOL1 
TP_BMC_GPIOL2 
TP_BMC_GPIOL3 
TP_BMC_GPIOL4 
TP_BMC_GPIOL5 
IOM_LOC_INS_N 
IOM_FULL_PWR_EN_R 
BMC_UART_SEL_OUT 
BMC_UART_SEL_IN 
SCC_RMT_FULL_PWR_EN 
SCC_RMT_TYPE_0_R 
SCC_LOC_FULL_PWR_EN 
CONN_A_PRSNTA 
LED_POSTCODE_0 
LED_POSTCODE_1 
LED_POSTCODE_2 
LED_POSTCODE_3 
LED_POSTCODE_4 
LED_POSTCODE_5 
LED_POSTCODE_6 
LED_POSTCODE_7 
DEBUG_RST_BTN_N 
DEBUG_RST_BTN_N 
NCSI_TXD0_R 
NCSI_TXD1_R 
SCC_STBY_PWR_EN 
50M_CLK_OUT 50M_CLK_OUT_R 
50M_CLK_OE 
NCSI_RCLK_R 
FLA1_SPI_RST 
TP_BMC_EXT1_LED_B 
BMC_EXT1_LED_Y 
TP_BMC_EXT2_LED_B 
BMC_EXT2_LED_Y 
UART_EXP_BMC_RX_R 
UART_EXP_BMC_TX_R 
EXP_UART_EN 
UART_EXP_BMC_RX 
UART_EXP_BMC_TX 
DPB_MISC_ALERT_OUT 
FLA1_SPI_RST 
TPM_PRSNT_N_R 
CLK_50M_BMC_NCSI U30_Q1 
IOM_FULL_PGOOD 
BMC_SELF_HW_RST 
BMC_ML_PWR_YELLOW_LED 
BMC_ML_PWR_BLUE_LED 
BMC_ML_PWR_YELLOW_LED 
BMC_ML_PWR_BLUE_LED 
PLTRST_R 
FLA1_WP_N 
P3V3_STBY 
P3V3_STBY 
P3V3_STBY 
P3V3_STBY 
P3V3_STBY 
P3V3_STBY P3V3_STBY 
P3V3_STBY 
P3V3_STBY 
P3V3_STBY 
P3V3_STBY P3V3_STBY P3V3_STBY 
BMC_SPI_MISO 17,24
NCSI_TXD0 12,24
NCSI_TXD1 12,24
NCSI_RXD0 12 
NCSI_RXD1 12 
NCSI_RCSDV 12 
NCSI_RX_ER 12 
UART_BMC_RX 26 
UART_BMC_TX 24,26 
FLA_CS_0_R 17 
BMC_SPI_CLK_R 17 
BMC_SPI_MOSI_R 17 SCC_LOC_FULL_PWR_EN 11
NCSI_TXEN 12,24
BMC_GPIOZ4 24
BMC_GPIOZ5 24
BMC_GPIOZ6 24
BMC_GPIOZ7 24
BMC_SPI_CLK 24 
BMC_SPI_MOSI 24 
BMC_GPIOS4 24 
BMC_GPIOS5 24 
BMC_GPIOS6 24 
BMC_GPIOS7 24 
MAC1_TXD2 24 
MAC1_TXD3 24 
MAC2_TXD0 24 
MAC2_TXD1 24 
MAC2_TXD2 24 
MAC2_TXD3 24 
MAC2_TXCTL 24 
I2C_MEZZ_ALERT_N 12
P12V_A_PGOOD 11,27
EXP_SPARE_1 11
EXP_SPARE_0 11
DPB_MISC_ALERT_OUT 18
SCC_STBY_PWR_EN 11
UART_BMC_COMP_IN_RX 26 
UART_COMP_OUT_TX 26 
IOM_LOC_INS_N 11 
IOM_FULL_PWR_EN 29
BMC_UART_SEL_OUT 26 
BMC_UART_SEL_IN 26 
SCC_RMT_FULL_PWR_EN 11
SCC_RMT_TYPE_0 11
CONN_A_PRSNTA 12
LED_POSTCODE_0 26
LED_POSTCODE_1 26
LED_POSTCODE_2 26
LED_POSTCODE_3 26
LED_POSTCODE_4 26
LED_POSTCODE_5 26
LED_POSTCODE_6 26
LED_POSTCODE_7 26
DEBUG_RST_BTN_N 22,26
NCSI_RCLK 12 
RST_BMC_EXTRST_N 17,22 
BMC_EXT1_LED_Y 46 
BMC_EXT2_LED_Y 46 
UART_EXP_BMC_RX 26
UART_EXP_BMC_TX 26
EXP_UART_EN 26 
FM_TPM_PRSNT_N 17
IOM_FULL_PGOOD 35,44 
BMC_SELF_HW_RST 17 
BMC_ML_PWR_YELLOW_LED 16
BMC_ML_PWR_BLUE_LED 16
PCIE_COMP_TO_IOM_RST_4 11,12,14,26
Title 
Size Document Number Rev
Date: Sheet 
of 
Bryce Canyon_IO Module 2
AST2500 UART LAN SPI 
A3 
21 47Friday, December 08, 2017 
Bryce Canyon_IO Module 
http://www.wiwynn.com 
8F, 90, Sec.1, Xintai 5th Rd., Xizhi Dist.,
New Taipei City 22102, Taiwan (R.O.C.)
Title 
Size Document Number Rev
Date: Sheet 
of 
Bryce Canyon_IO Module 2
AST2500 UART LAN SPI 
A3 
21 47Friday, December 08, 2017 
Bryce Canyon_IO Module 
http://www.wiwynn.com 
8F, 90, Sec.1, Xintai 5th Rd., Xizhi Dist.,
New Taipei City 22102, Taiwan (R.O.C.)
Title 
Size Document Number Rev
Date: Sheet 
of 
Bryce Canyon_IO Module 2
AST2500 UART LAN SPI 
A3 
21 47Friday, December 08, 2017 
Bryce Canyon_IO Module 
http://www.wiwynn.com 
8F, 90, Sec.1, Xintai 5th Rd., Xizhi Dist.,
New Taipei City 22102, Taiwan (R.O.C.)
TP190 1
R288 0 ohm 0402 12
TP27 1
TP186 1
C76 
SCD01U25V2KX-3GP 
0.01uF 
25V 
10% 
0402 
X7R 
1 2
TP28 1
R708 
10KR2F-2-GP 
10k ohm 
1/16W 
1% 
0402 
1 2
TP29 1
R297 0 ohm 0402 12
TP191 1
R599 
4K7R2F-GP 
4.7k ohm 
1/16W 
1% 
0402 
1 2
R292 0R2J-2-GP 
0 ohm 1/16W 5% 0402 
12
R295 0 ohm 0402 12
R305 
10KR2F-2-GP 
10k ohm 
1/16W 
1% 
0402 
1 2
R283 33 ohm 0402 1 2
R270 33R2F-3-GP 
33 ohm 1/16W 1% 0402 
1 2
R265 4.7k ohm 0402 1 2
R269 
2K2R2J-2-GP 
2.2k ohm 
1/16W 
5% 
0402 
NOPOP 
1 2
R610 
100KR2F-L1-GP 
100k ohm 
1/16W 
1% 
0402 
1 2
R289 0 ohm 0402 12
R267 
2K2R2J-2-GP 
2.2k ohm 
1/16W 
5% 
0402 
1 2
R268 
2K2R2J-2-GP 
2.2k ohm 
1/16W 
5% 
0402 
1 2 BMC SPI 
BMC/System 
   UART 
MAC1 
MAC2 
SPI2 ACPI 
Digital Video 
   Output 
2 OF 4 U2B 
AST2500A2-GP-GP-U 
RGMIICK D3 
RGMII1RXCK_RMII1RCLKI_GPIOU4 B4 
RGMII1RXCTL_GPIOU5 A4 
RGMII1RXD0_RMII1RXD0_GPIOU6 A3 
RGMII1RXD1_RMII1RXD1_GPIOU7 D6 
RGMII1RXD2_RMII1CRSDV_GPIOV0 C5 
RGMII1RXD3_RMII1RXER_GPIOV1 C4 
RGMII1TXCK_RMII1RCLKO_GPIOT0 B5 
RGMII1TXCTL_RMII1TXEN_GPIOT1 E9 
RGMII1TXD0_RMII1TXD0_GPIOT2 F9 
RGMII1TXD1_RMII1TXD1_GPIOT3 A5 
RGMII1TXD2_GPIOT4 E7 
RGMII1TXD3_GPIOT5 D7 
RGMII2RXCK_RMII2RCLKI_GPIOV2 C2 
RGMII2RXCTL_GPIOV3 C1 
RGMII2RXD0_RMII2RXD0_GPIOV4 C3 
RGMII2RXD1_RMII2RXD1_GPIOV5 D1 
RGMII2RXD2_RMII2CRSDV_GPIOV6 D2 
RGMII2RXD3_RMII2RXER_GPIOV7 E6 
RGMII2TXCK_RMII2RCLKO_GPIOT6 B2 
RGMII2TXCTL_RMII2TXEN_GPIOT7 B1 
RGMII2TXD0_RMII2TXD0_GPIOU0 A2 
RGMII2TXD1_RMII2TXD1_GPIOU1 B3 
RGMII2TXD2_GPIOU2 D5 
RGMII2TXD3_GPIOU3 D4 
GPIOA6_TIMER7_MDC2 C13 
GPIOA7_TIMER8_MDIO2 B13 
GPIOR6_MDC1 D8 
GPIOR7_MDIO1 E10 
FWSPICS0# AB19 
GPIOL0_NCTS1 T2 
GPIOL1_NDCD1_VPIDE T1 
GPIOL2_NDSR1 U1 
GPIOL3_NRI1_VPIHS U2 
GPIOL4_NDTR1_VPIVS P4 
GPIOL5_NRTS1_VPICLK P3 
GPIOL6_TXD1 V1 
GPIOL7_RXD1 W1 
GPIOM0_NCTS2_VPIB2 Y1 
GPIOM1_NDCD2_VPIB3 AB2 
GPIOM2_NDSR2_VPIB4 AA1 
GPIOM3_NRI2_VPIB5 Y2 
GPIOM4_NDTR2_VPIB6 AA2 
GPIOM5_NRTS2_VPIB7 P5 
GPIOM6_TXD2_VPIB8 R5 
GPIOM7_RXD2_VPIB9 T5 
GPIOE0_NCTS3 B20 
GPIOE1_NDCD3 C20 
GPIOE2_NDSR3 F18 
GPIOE3_NRI3 F17 
GPIOE4_NDTR3 E18 
GPIOE5_NRTS3 D19 
GPIOE6_TXD3 A20 
GPIOE7_RXD3 B19 
GPIOF0_NCTS4_LHAD0 J19 
GPIOF1_NDCD4_LHAD1 J18 
GPIOF2_NDSR4_LHAD2 B22 
GPIOF3_NRI4_LHAD3 B21 
GPIOF4_NDTR4_LHCLK A21 
GPIOF5_NRTS4_LHFRAME# H19 
GPIOF6_TXD4_LHSIRQ# G17 
GPIOF7_RXD4_LHRST# H18 
RXD5 K2 TXD5 K1 
GPIOR0_FWSPICS1# AA19 
GPIOR1_FWSPICS2# T19 
GPIOR2_SPI2CS0# T17 
GPIOR3_SPI2CK Y19 
GPIOR4_SPI2MOSI W19 
GPIOR5_SPI2MISO V19 
GPIOZ0_VPOG2_NORA0_SIOPBI# Y20 
GPIOZ1_VPOG3_NORA1_SIOPWRGD AB20 
GPIOZ2_VPOG4_NORA2_SIOPBO# AB21 
GPIOZ3_VPOG5_NORA3_SIOSCI# AA21 
GPIOZ4_VPOG6_NORA4 U21 
GPIOZ5_VPOG7_NORA5 W22 
GPIOZ6_VPOG8_NORA6 V22 
GPIOZ7_VPOG9_NORA7 W21 
GPIOAA0_VPOR2_NORD0_SALT7 Y21 
GPIOAA1_VPOR3_NORD1_SALT8 V21 
GPIOAA2_VPOR4_NORD2_SALT9 Y22 
GPIOAA3_VPOR5_NORD3_SALT10 AA22 
GPIOAA4_VPOR6_NORD4_SALT11 U22 
GPIOAA5_VPOR7_NORD5_SALT12 T20 
GPIOAA6_VPOR8_NORD6_SALT13 N18 
GPIOAA7_VPOR9_NORD7_SALT14 P19 
GPIOY0_SIOS3# R22 
GPIOY1_SIOS5# R21 
GPIOY2_SIOPWREQ# P22 
GPIOY3_SIOONCTRL# P21 
GPIOAB0_VPODE_NOROE# N19 
GPIOAB1_VPOHS_NORWE# T21 
GPIOAB2_VPOVS_WDTRST1 T22 
GPIOAB3_VPOCLK_WDTRST2 R20 
GPIOS0_VPOB2_SPI2CS1# V20 
GPIOS1_VPOB3_BMCINT U19 
GPIOS2_VPOB4_SALT5 R18 
GPIOS3_VPOB5_SALT6 P18 
GPIOS4_VPOB6 R19 
GPIOS5_VPOB7 W20 
GPIOS6_VPOB8 U20 
GPIOS7_VPOB9 AA20 
GPIOH4_NDTR6 A17 
GPIOH5_NRTS6 B17 
GPIOH6_TXD6 A16 
GPIOH7_RXD6 D18 
GPIOH0_NCTS6 A18 
GPIOH1_NDCD6 B18 
GPIOH2_NDSR6 D17 
GPIOH3_NRI6 C17 
FWSPICK AA18 
FWSPIMOSI U17 
FWSPIMISO T18 
U30 
ICS551MLFT-GP 
ICLK 1 Q1 2
Q2 3
Q3 4
Q4 5
GND 6VDD 7
OE 8
R87 
100KR2F-L1-GP 
100k ohm 
1/16W 
1% 
0402 
NOPOP 
1 2
R262 4.7k ohm 0402 1 2
TP192 1
R276 4.7k ohm 0402 1 2
R264 4.7k ohm 0402 1 2
R327 
4K7R2F-GP 
4.7k ohm 
1/16W 
1% 
0402 
1 2
R301 0 ohm 0402 12
R298 0 ohm 0402 12
R763 33R2J-2-GP 
33 ohm 1/16W 5% 0402 
1 2
R293 0 ohm 0402 12
TP193 1
R780 33R2J-2-GP 
33 ohm 1/16W 5% 0402 
1 2
R611 4.7k ohm 0402 NOPOP 1 2
R263 4.7k ohm 0402 1 2
U29 
MX25L25635FMI-10G-GP 
DNU/SIO3 1
VCC 2
CS# 7
SO/SIO1 8
WP#/SIO2 9
GND 10 
SI/SIO0 15 
SCLK 16 
RESET# 3
NC#4 4
NC#5 5
NC#6 6
NC#11 11 
NC#12 12 
NC#13 13 
NC#14 14 
R334 0 ohm 0402 12
R330 
4K7R2F-GP 
4.7k ohm 
1/16W 
1% 
0402 
NOPOP 
1 2
TP50 1
R290 0 ohm 0402 12
R266 
2K2R2J-2-GP 
2.2k ohm 
1/16W 
5% 
0402 
1 2
R335 0 ohm 0402 12
R286 0 ohm 0402 12R284 33 ohm 0402 1 2
R612 4.7k ohm 0402 NOPOP 1 2
SKT2 
SKT-SPI16P-GP-U 
1
2
3
4
5
6
7
8
16 
15 
14 
13 
12 
11 
10 
9
TP52 1
X2 
OSC-50MHZ-16-GP 
TRI-STATE 1
GND 2 OUTPUT 3VDD 4
R277 33 ohm 0402 1 2
C75 
SCD1U16V2KX-3GP 
0.1uF 
16V 
10% 
0402 
X7R 
1 2
R613 0 ohm 0402 12
TP18 1
TP187 1
TP51 1
R291 0 ohm 0402 12
TP53 1
R306 33R2J-2-GP 
33 ohm 1/16W 5% 0402 
1 2
R287 0 ohm 0402 NOPOP 12
R302 0 ohm 0402 12
TP188 1
C74 
SCD1U16V2KX-3GP 
0.1uF 
16V 
10% 
0402 
X7R 
1 2
R299 
4K7R2F-GP 
4.7k ohm 
1/16W 
1% 
0402 
1 2
R304 47KR2F-GP 
47k ohm 1/16W 1% 0402 
1 2
R350 0 ohm 0402 12
R88 
100KR2F-L1-GP 
100k ohm 
1/16W 
1% 
0402 
1 2
TP17 1
R280 33 ohm 0402 1 2
R764 0 ohm 0402 NOPOP 12
TP189 1
R300 
4K7R2F-GP 
4.7k ohm 
1/16W 
1% 
0402 
NOPOP 
1 2
R294 0 ohm 0402 12
TP54 1
TP55 1
R303 47KR2F-GP 
47k ohm 1/16W 1% 0402 
1 2
R328 0 ohm 0402 12
R307 10KR2F-2-GP 
10k ohm 1/16W 1% 0402 
1 2



5
5
4
4
3
3
2
2
1
1
D D
C C
B B
A A
JTAG 
JTAG_BMC_TRST_N 
BMC0_JTAG_RTCK 
JTAG_BMC_TDI 
JTAG_BMC_TMS 
JTAG_BMC_TCK 
JTAG_BMC_TDO 
BOARD_REV_0 
BOARD_REV_1 
BOARD_REV_2 
COMP_POWER_FAIL_N 
FAN_PWM0_BMC 
TP_BMC_GPION2 
TP_BMC_GPION4 
TP_BMC_GPION5 
TP_BMC_GPION7 
PD_USB2BVRES 
BOARD_REV_0 
BOARD_REV_1 
BOARD_REV_2 
SLOTID_0 
SLOTID_1 
TP_BMC_GPIOI4 
TP_BMC_GPIOI5 
TP_BMC_GPIOI6 
TP_BMC_GPIOI7 
SLOTID_1 SLOTID_0 
TP_BMC_GPIOI0 
TP_BMC_GPIOI1 
TP_BMC_GPIOI2 
TP_BMC_GPIOI3 
PECI 
JTAG_BMC_TDO 
JTAG_BMC_TMS 
JTAG_BMC_TDI 
JTAG_BMC_TCK 
BMC0_JTAG_RTCK 
JTAG_BMC_TRST_N 
BMC_LOC_HB 
BMC_RMT_HB 
ENCL_FAULT_LED_R 
SCC_A_HB_IN_R 
SCC_B_HB_IN_R 
COMP_POWER_FAIL_R_N 
OSC_OUT 
CLKIN_24M_BMC OSC_OUT 
OSC_OE 
BMC_ENTEST 
BMC0_SRST_N FM_BMC_RESET_N 
BMC_EXTRST_N 
BMC_HBLED_R 
BMC_HBLED 
BMC_HBLED 
TP_BMC_GPION6 
I2C_COMP_ALERT_N 
TP_BMC_GPIOG5 
TP_BMC_GPIOG6 
PD_USB2AVRES 
FM_BMC_RESET_N 
TP_BMC_GPION3 
THROTTLE_N 
COMP_TO_BMC_RESET_N_OUT 
FAN_PWM1_BMC 
COMP_TO_BMC_RESET_N_OUT 
BMC_TPM_RST_N 
RST_BMC_EXTRST_N_1 
RST_BMC_EXTRST_N 
RST_BMC_EXTRST_N_1 
ENCL_FAULT_LED 
COMP_FAST_THROTTLE_N 
DEBUG_GPIO_BMC_R_1 
DEBUG_GPIO_BMC_R_2 
DEBUG_GPIO_BMC_R_3 
DEBUG_GPIO_BMC_R_4 
DEBUG_GPIO_BMC_R_5 
DEBUG_GPIO_BMC_R_6 
I2C_COMP_ALERT_N 
COMP_PWR_EN_R 
FLA0_WP_N_R 
PCIE_WAKE_N 
PCIE_WAKE_N 
COMP_SPARE_0_R 
COMP_SPARE_1_R 
DEBUG_RST_BTN_N_R 
DEBUG_RST_BTN_N_R 
RST_BMC_EXTRST_N_1 IOM_TYPE0 
IOM_TYPE1 
IOM_TYPE2 
IOM_TYPE3 
IOM_TYPE1 
IOM_TYPE2 
IOM_TYPE3 
IOM_TYPE0 
P3V3_STBY 
P3V3_STBY P3V3_STBY P3V3_STBY P3V3_STBY P3V3_STBY P3V3_STBY 
P3V3_STBY 
P3V3_STBY 
P3V3_STBY 
P3V3_STBY P3V3_STBY 
P1V15_STBY 
P3V3_STBY 
P3V3_STBY 
P3V3_STBY 
P3V3_STBY 
P3V3_STBY 
P3V3_STBY P3V3_STBY P3V3_STBY 
P3V3_STBY 
P3V3_STBY 
P3V3_STBY 
PWM_OUT_ZONE_C 11 
SLOTID_0 11 
SLOTID_1 11 
BMC_RMT_HEARTBEAT 11 
BMC_LOC_HEARTBEAT 11 
ENCL_FAULT_LED 11 
SCC_LOC_HEARTBEAT 11 
SCC_RMT_HEARTBEAT 11 
COMP_POWER_FAIL_N 11 
I2C_COMP_ALERT_N 18 
PWM_OUT_ZONE_D 11 
COMP_TO_BMC_RESET_N_OUT 18 
BMC_TPM_RST_N 17 
IOM_STBY_PGOOD 29,33 
FM_BMC_RESET_N 17 
DEBUG_RST_BTN_N 21,26 
ADC_P5V_STBY 25 
ADC_P3V3_STBY 25 
ADC_P1V8_STBY 25 
ADC_12V 25 
DEBUG_GPIO_BMC_1 26 
DEBUG_GPIO_BMC_2 26 
DEBUG_GPIO_BMC_3 26 
DEBUG_GPIO_BMC_4 26 
DEBUG_GPIO_BMC_5 26 
DEBUG_GPIO_BMC_6 26 
ADC_P1V5 25 
ADC_P0V975 25 
ADC_P3V3 25 
ADC_P1V8 25 
ADC_P2V5_STBY 25 
ADC_P1V2_STBY 25 
ADC_P1V15_STBY 25 
COMP_FAST_THROTTLE_N 11 
USB_P2_DP 14 
USB_P2_DN 14 
USB_P3_DP 14 
USB_P3_DN 14 
COMP_PWR_EN 11,18 
FLA0_WP_N 17 
PCIE_WAKE_N 12 
COMP_SPARE_0 11 
COMP_SPARE_1 11 
RST_BMC_EXTRST_N 17,21 
SYS_RST_EN 18 
Title 
Size Document Number Rev
Date: Sheet 
of 
Bryce Canyon_IO Module 2
AST2500 FAN ADC VGA 
A3 
22 47 Friday, December 08, 2017 
Bryce Canyon_IO Module 
http://www.wiwynn.com 
8F, 90, Sec.1, Xintai 5th Rd., Xizhi Dist.,
New Taipei City 22102, Taiwan (R.O.C.)
Title 
Size Document Number Rev
Date: Sheet 
of 
Bryce Canyon_IO Module 2
AST2500 FAN ADC VGA 
A3 
22 47 Friday, December 08, 2017 
Bryce Canyon_IO Module 
http://www.wiwynn.com 
8F, 90, Sec.1, Xintai 5th Rd., Xizhi Dist.,
New Taipei City 22102, Taiwan (R.O.C.)
Title 
Size Document Number Rev
Date: Sheet 
of 
Bryce Canyon_IO Module 2
AST2500 FAN ADC VGA 
A3 
22 47 Friday, December 08, 2017 
Bryce Canyon_IO Module 
http://www.wiwynn.com 
8F, 90, Sec.1, Xintai 5th Rd., Xizhi Dist.,
New Taipei City 22102, Taiwan (R.O.C.)
TP71 1
R770 0 ohm 0402 12
R700 
4K7R2F-GP 
NOPOP 
4.7k ohm 
1/16W 
1% 
0402 
1 2
TP77 1
OSC1 
OSC-24MHZ-18-GP 
OE 1
GND 2
OUTPUT 3
VDD 4
R332 
4K7R2F-GP 
4.7k ohm 
1/16W 
1% 
0402 
NOPOP 
1 2
R343 0 ohm 0402 12
R355 
4K7R2F-GP 
NOPOP 
4.7k ohm 
1/16W 
1% 
0402 
1 2
U37 
SN74LVC1G08DCKR-GP 
B2
A1
GND 3 Y 4
VCC 5
C81 
SC4D7U25V5KX-1-GP 
4.7uF 
25V 
10% 
0805 
X7R 
1 2
R354 
4K7R2F-GP 
NOPOP 
4.7k ohm 
1/16W 
1% 
0402 
1 2
TP81 1
R362 
4K7R2F-GP 
NOPOP 
4.7k ohm 
1/16W 
1% 
0402 
1 2
R357 
4K7R2F-GP 
NOPOP 
4.7k ohm 
1/16W 
1% 
0402 
1 2
R348 0 ohm 0402 NOPOP 12
TP57 1
R319 0 ohm 0402 12
R351 10KR2F-2-GP 
10k ohm 1/16W 1% 0402 
1 2
TP83 1
R363 
4K7R2F-GP 
NOPOP 
4.7k ohm 
1/16W 
1% 
0402 
1 2
R316 0 ohm 0402 12
R731 0 ohm 0402 12
R703 
4K7R2F-GP 
4.7k ohm 
1/16W 
1% 
0402 
12
TP82 1
R782 
4K7R2F-GP 
4.7k ohm 
1/16W 
1% 
0402 
NOPOP 
1 2
R331 
4K7R2F-GP 
4.7k ohm 
1/16W 
1% 
0402 
1 2
TP75 1
DAC 
USB 
PECI 
FAN 
ADC 
JTAG 
SGPIO 
MISC 
System 
  SPI 
3 OF 4 U2C 
AST2500A2-GP-GP-U 
DACB J2 
DACG J3 
DACR J4 
PECIVDD AA17 
PECI AB18 
USB2AV33 C7 
USB2AVRES B8 
USB2A_DN A8 USB2A_DP A7 
USB2BVRES B7 
USB2B_DN A6 USB2B_DP B6 
ADC0_GPIW0 F4 
ADC1_GPIW1 F5 
ADC2_GPIW2 E2 
ADC3_GPIW3 E1 
ADC4_GPIW4 F3 
ADC5_GPIW5 E3 
ADC6_GPIW6 G5 
ADC7_GPIW7 G4 
ADC8_GPIX0 F2 
ADC9_GPIX1 G3 
ADC10_GPIX2 G2 
ADC11_GPIX3 F1 
ADC12_GPIX4 H5 
ADC13_GPIX5 G1 
ADC14_GPIX6 H3 
ADC15_GPIX7 H4 
ENTEST K3 
SRST# U18 
EXTRST# V18 
CLKIN W18 
HBLED# Y18 
NTRST E11 
TCK C10 
TDI D12 
TDO D11 
TMS C8 
RTCK C9 
GPIOJ4_VGAHS N5 
GPIOJ5_VGAVS R4 
GPIOJ6_DDCCLK R3 
GPIOJ7_DDCDAT T3 
GPIOJ0_SGPMCK R2 
GPIOJ1_SGPMLD L2 
GPIOJ2_SGPMO N3 
GPIOJ3_SGPMI N4 
GPIOG0_SGPS1CK A19 
GPIOG1_SGPS1LD E19 
GPIOG2_SGPS1I0 C19 
GPIOG3_SGPS1I1 E16 
GPIOG4_SGPS2CK_SALT1 E17 
GPIOG5_SGPS2LD_SALT2 D16 
GPIOG6_SGPS2I0_SALT3 D15 
GPIOG7_SGPS2I1_SALT4 E14 
GPION0_PWM0 V2 
GPION1_PWM1 W2 
GPION2_PWM2_VPIG2 V3 
GPION3_PWM3_VPIG3 U3 
GPION4_PWM4_VPIG4 W3 
GPION5_PWM5_VPIG5 AA3 
GPION6_PWM6_VPIG6 Y3 
GPION7_PWM7_VPIG7 T4 
GPIOO0_TACH0_VPIG8 U5 
GPIOO1_TACH1_VPIG9 U4 
GPIOO2_TACH2 V5 
GPIOO3_TACH3 AB4 
GPIOO4_TACH4_VPIR2 AB3 
GPIOO5_TACH5_VPIR3 Y4 
GPIOO6_TACH6_VPIR4 AA4 
GPIOO7_TACH7_VPIR5 W4 
GPIOP0_TACH8_VPIR6 V4 
GPIOP1_TACH9_VPIR7 W5 
GPIOP2_TACH10_VPIR8 AA5 
GPIOP3_TACH11_VPIR9 AB5 
GPIOP4_TACH12 Y6 
GPIOP5_TACH13 Y5 
GPIOP6_TACH14 W6 
GPIOP7_TACH15 V6 
GPIOI4_SPI1CS0#_VBCS# B15 
GPIOI5_SPI1CK_VBCK C15 
GPIOI6_SPI1MOSI_VBMOSI A14 
GPIOI7_SPI1MISO_VBMISO A15 
GPIOI0_SYSCS# C18 
GPIOI1_SYSCK E15 
GPIOI2_SYSMOSI B16 
GPIOI3_SYSMISO C16 
R315 10KR2F-2-GP 
10k ohm 1/16W 1% 0402 
12
TP80 1
TP76 1
TP79 1
R324 
4K7R2F-GP
4.7k ohm
1/16W 
1% 
0402 
1 2
R312 0 ohm 0402 12
U31 
SN74LVC1G08DCKR-GP 
B2
A1
GND 3 Y 4
VCC 5
R317 0 ohm 0402 12
C505 
SCD1U16V2KX-3GP 
0.1uF 
16V 
10% 
0402 
X7R 
1 2
R707 
4K7R2F-GP 
NOPOP 
4.7k ohm 
1/16W 
1% 
0402 
1 2
R340 8.2k ohm 0402 1 2
R309 
4K7R2F-GP 
NOPOP 
4.7k ohm 
1/16W 
1% 
0402 
1 2
TP65 1
R771 0 ohm 0402 12
R786 0 ohm 0402 NOPOP 12
R365 
4K7R2F-GP 
NOPOP 
4.7k ohm 
1/16W 
1% 
0402 
1 2
R338 8.2k ohm 0402 1 2
R352 
4K7R2F-GP 
4.7k ohm 
1/16W 
1% 
0402 
1 2
TP69 1
R333 0 ohm 0402 12
R325 0 ohm 0402 12
R361 
10KR2F-2-GP 
10k ohm 
1/16W 
1% 
0402 
1 2
C78 
SCD1U16V2KX-3GP 
0.1uF 
16V 
10% 
0402 
X7R 
1 2
R706 
4K7R2F-GP 
4.7k ohm 
1/16W 
1% 
0402 
12
R358 
10KR2F-2-GP 
10k ohm 
1/16W 
1% 
0402 
1 2
R320 0 ohm 0402 12
R326 0 ohm 0402 12
R360 
10KR2F-2-GP 
10k ohm 
1/16W 
1% 
0402 
1 2
R323 
4K7R2F-GP 
4.7k ohm 
1/16W 
1% 
0402 
NOPOP 
12
R359 
10KR2F-2-GP 
10k ohm 
1/16W 
1% 
0402 
1 2
R353 
4K7R2F-GP 
4.7k ohm 
1/16W 
1% 
0402 
1 2
R601 
4K7R2F-GP 
4.7k ohm 
1/16W 
1% 
0402 
1 2
TP73 1
R772 0 ohm 0402 12
R346 
150R2F-1-GP 
150 ohm 
1/16W 
1% 
0402 
1 2
R740 
4K7R2F-GP 
4.7k ohm 
1/16W 
1% 
0402 
12
TP78 1
R356 0R2J-2-GP 
0 ohm 1/16W 5% 0402 
1 2
TP74 1
TP70 1
R697 
4K7R2F-GP 
4.7k ohm 
1/16W 
1% 
0402 
1 2
TP62 1
R714 0 ohm 0402 12
R345 0 ohm 0402 NOPOP 12
R311 
4K7R2F-GP
4.7k ohm
1/16W 
1% 
0402 
NOPOP
12
TP66 1
R313 
4K7R2F-GP 
4.7k ohm 
1/16W 
1% 
0402 
12
C82 SC33P50V2JN-3GP 
33pF 50V 5% 0402 NPO 
1 2
R321 0 ohm 0402 12
TP68 1
R314 0 ohm 0402 12
C83 
SC1U16V3KX-5GP 
1uF 
16V 
10% 
0603 
X7R 
NOPOP 
1 2
R702 
4K7R2F-GP 
4.7k ohm 
1/16W 
1% 
0402 
1 2
LED6 
LED-YG-51-GP 
A K
R310 
4K7R2F-GP 
4.7k ohm 
1/16W 
1% 
0402 
1 2
R773 0 ohm 0402 12
R701 
4K7R2F-GP 
4.7k ohm 
1/16W 
1% 
0402 
1 2
R364 
4K7R2F-GP 
NOPOP 
4.7k ohm 
1/16W 
1% 
0402 
1 2
R699 
4K7R2F-GP 
NOPOP 
4.7k ohm 
1/16W 
1% 
0402 
1 2
R698 
4K7R2F-GP 
NOPOP 
4.7k ohm 
1/16W 
1% 
0402 
1 2
C80 
SCD1U16V2KX-3GP 
0.1uF 
16V 
10% 
0402 
X7R 
1 2
TP72 1
R336 
4K7R2F-GP 
4.7k ohm 
1/16W 
1% 
0402 
NOPOP 
1 2
R768 0 ohm 0402 12
R308 
4K7R2F-GP 
4.7k ohm 
1/16W 
1% 
0402 
1 2
R705 
4K7R2F-GP 
4.7k ohm 
1/16W 
1% 
0402 
12
R769 0 ohm 0402 12
C79 
SCD1U16V2KX-3GP 
0.1uF 
16V 
10% 
0402 
X7R 
1 2
R322 0 ohm 0402 12
TP64 1
R318 0 ohm 0402 12
TP84 1
TP63 1



5
5
4
4
3
3
2
2
1
1
D D
C C
B B
A A
V1PLLAV11 
MPLLAV33 
ADCAV33 
ADCAV33 
ADCVREFFN 
ADCVREFFP 
ADCVREXT 
DACRSET 
DACAV33 
DACAV33 
MPLLAV33 
VPLLAV33 
VPLLAV33 
V1PLLAV11 
MPLLAV33 
P3V3_STBY 
P1V15_STBY 
P3V3_STBY 
P3V3_STBY 
P1V15_STBY 
P3V3_STBY 
P1V2_STBY 
P3V3_STBY 
P3V3_STBY 
P1V15_STBY 
P1V15_STBY 
P3V3_STBY 
P3V3_STBY 
P3V3_STBY 
P3V3_STBY 
P1V8_STBY 
P1V8_STBY 
Title 
Size Document Number Rev
Date: Sheet 
of 
Bryce Canyon_IO Module 2
AST2500 Power 
A3 
23 47 Friday, December 08, 2017 
Bryce Canyon_IO Module 
http://www.wiwynn.com 
8F, 90, Sec.1, Xintai 5th Rd., Xizhi Dist.,
New Taipei City 22102, Taiwan (R.O.C.)
Title 
Size Document Number Rev
Date: Sheet 
of 
Bryce Canyon_IO Module 2
AST2500 Power 
A3 
23 47 Friday, December 08, 2017 
Bryce Canyon_IO Module 
http://www.wiwynn.com 
8F, 90, Sec.1, Xintai 5th Rd., Xizhi Dist.,
New Taipei City 22102, Taiwan (R.O.C.)
Title 
Size Document Number Rev
Date: Sheet 
of 
Bryce Canyon_IO Module 2
AST2500 Power 
A3 
23 47 Friday, December 08, 2017 
Bryce Canyon_IO Module 
http://www.wiwynn.com 
8F, 90, Sec.1, Xintai 5th Rd., Xizhi Dist.,
New Taipei City 22102, Taiwan (R.O.C.)
C116 
SC4D7U25V5KX-1-GP 
4.7uF 
25V 
10% 
0805 
X7R 
1 2
4 OF 4 U2D 
AST2500A2-GP-GP-U 
GND A1 
GND A22 
GND AA11 
GND AA13 
GND AA15 
GND AA7 
GND AA9 
GND AB1 
GND AB22 
GND C6 
GND E8 
GND F16 
GND G19 
GND G6 
GND H6 
GND J10 
GND J11 
GND J12 
GND J13 
GND J14 
GND J21 
GND J22 
GND J5 
GND J9 
GND K10 
GND K11 
GND K12 
GND K13 
GND K14 
GND K16 
GND K9 
GND L10 
GND L11 
GND L12 
GND L13 
GND L14 
GND L9 
GND M1 
GND M10 
GND M11 
GND M12 
GND M13 
GND M14 
GND M16 
GND M17 
GND M2 
GND M3 
GND M4 
GND M5 
GND M6 
GND M7 
GND M9 
GND N10 
GND N11 
GND N12 
GND N13 
GND N14 
GND N9 
GND T16 
GND T6 
GND T7 
GND U11 
GND U6 
GND V10 
GND V12 
GND V14 
GND V16 
GND V8 
GND E5 
PEAV11 L17 
PEAV33 L16 
ADCREXT J1 
ADCVREFN H1 
ADCVREFP H2 
ADCAV33 J6 
DACAV33 K6 
DACDV33 K5 
DACRSET K4 
PLLAV33 W17 
PLLAV33 Y17 
PLLDV11 V17 
VPLLAV33 J7 
VPLLAV33 H7 
VPLLAV11 L5 
VPLLAV11 L6 
BATVDD E4 
IV11D F6 
IV11D G10 
IV11D G11 
IV11D G12 
IV11D G13 
IV11D G14 
IV11D G15 
IV11D G7 
IV11D G8 
IV11D G9 
IV11D H16 
IV11D J16 
IV11D L7 
IV11D N16 
IV11D N7 
IV11D P10 
IV11D P11 
IV11D P12 
IV11D P13 
IV11D P14 
IV11D P16 
IV11D P7 
IV11D P9 
IV11D R16 
IV11D R7 
PV33D F12 
PV33D F13 
PV33D F14 
PV33D F15 
PV33D G16 
PV33D H17 
PV33D K7 
PV33D N17 
PV33D N6 
PV33D P17 
PV33D P6 
PV33D R17 
PV33D R6 
MPLLAV33 T11 
PV33D T15 
R1VDD F10 
R1VDD F11 
R2VDD F7 
R2VDD F8 
MVDD T10 
MVDD T12 
MVDD T13 
MVDD T14 
MVDD T8 
LPVDD J17 
LPVDD K17 
C89 
SC4D7U25V5KX-1-GP 
4.7uF 
25V 
10% 
0805 
X7R 
1 2
C108 
SC1U16V3KX-5GP 
1uF 
16V 
10% 
0603 
X7R 
1 2
L5 
MMZ2012S601ATA1N-GP 
68.00109.171 
600Ohm@100MHz 
Imax=0.5A 
DCR=300mOhm 
Tmax=150C 
1 2
C88 
SC100P50V2JN-3GP 
100pF 
50V 
5% 
0402 
NPO 
1 2
C999 
SCD1U16V2KX-3GP 
0.1uF 
16V 
10% 
0402 
X7R 
1 2
C86 
SCD1U16V2KX-3GP 
NOPOP 
0.1uF 
16V 
10% 
0402 
X7R 
1 2
C99 
SC1U16V3KX-5GP 
1uF 
16V 
10% 
0603 
X7R 
1 2
C998 
SC1U16V3KX-5GP 
1uF 
16V 
10% 
0603 
X7R 
1 2
C84 
SCD1U16V2KX-3GP 
NOPOP 
0.1uF 
16V 
10% 0402 X7R 
1 2
C94 
SC100P50V2JN-3GP 
100pF 
50V 
5% 
0402 
NPO 
1 2
R368 0R2J-2-GP 
0 ohm 
1/16W 
5% 
0402 
1 2
C104 
SC10U6D3V3KX-1-GP 
10uF 
6.3V 
10% 
0603 
X6S 
12
C103 
SCD1U16V2KX-3GP 
0.1uF 
16V 
10% 
0402 
X7R 
1 2
C101 
SC1U16V3KX-5GP 
1uF 
16V 
10% 
0603 
X7R 
1 2
C92 
SC1U16V3KX-5GP 
1uF 
16V 
10% 
0603 
X7R 
1 2
C102 
SC1U16V3KX-5GP 
1uF 
16V 
10% 
0603 
X7R 
1 2
C106 
SC4D7U25V5KX-1-GP 
4.7uF 
25V 
10% 
0805 
X7R 
1 2
C85 
SCD1U16V2KX-3GP 
NOPOP 
0.1uF 
16V 10% 0402 
X7R 1 2
C95 
SC1U16V3KX-5GP 
1uF 
16V 
10% 
0603 
X7R 
1 2
C107 
SC1U16V3KX-5GP 
1uF 
16V 
10% 
0603 
X7R 
1 2
C96 
SC100P50V2JN-3GP 
100pF 
50V 
5% 
0402 
NPO 
1 2
C87 
SC1U16V3KX-5GP 
1uF 
16V 
10% 
0603 
X7R 
1 2
C115 
SC10U6D3V3KX-1-GP 
10uF 
6.3V 
10% 
0603 
X6S 
12
C97 
SC1U16V3KX-5GP 
1uF 
16V 
10% 
0603 
X7R 
1 2
C100 
SC1U16V3KX-5GP 
1uF 
16V 
10% 
0603 
X7R 
1 2
C113 
SC1U16V3KX-5GP 
1uF 
16V 
10% 
0603 
X7R 
1 2
R367 18KR2F-5-GP 
18k ohm 1/16W 1% 0402 
1 2
C98 
SC1U16V3KX-5GP 
1uF 
16V 
10% 
0603 
X7R 
1 2
L2 
MMZ2012S601ATA1N-GP 
68.00109.171 
600Ohm@100MHz 
Imax=0.5A 
DCR=300mOhm 
Tmax=150C 
1 2
C93 
SCD1U16V2KX-3GP 
0.1uF 
16V 
10% 
0402 
X7R 
1 2
L4 
MMZ2012S601ATA1N-GP 
68.00109.171 
600Ohm@100MHz 
Imax=0.5A 
DCR=300mOhm 
Tmax=150C 
1 2
C91 
SC100P50V2JN-3GP 
100pF 
50V 
5% 
0402 
NPO 
1 2
C105 
SC100P50V2JN-3GP 
100pF 
50V 
5% 
0402 
NPO 
1 2
R366 49K9R2F-L-GP 
49.9k ohm 1/16W 1% 0402 
1 2
L3 
MMZ2012S601ATA1N-GP 
68.00109.171 
600Ohm@100MHz 
Imax=0.5A 
DCR=300mOhm 
Tmax=150C 
1 2
C110 
SC1U16V3KX-5GP 
1uF 
16V 
10% 
0603 
X7R 
1 2
C109 
SC1U16V3KX-5GP 
1uF 
16V 
10% 
0603 
X7R 
1 2
C114 
SC1U16V3KX-5GP 
1uF 
16V 
10% 
0603 
X7R 
1 2
C90 
SC1U16V3KX-5GP 
1uF 
16V 
10% 
0603 
X7R 
1 2



5
5
4
4
3
3
2
2
1
1
D D
C C
B B
A A
8/23 modified 
BMC_SPI_CLK 
BMC_SPI_MISO 
BMC_SPI_MOSI 
NCSI_TXEN 
NCSI_TXD0 
NCSI_TXD1 
MAC1_TXD2 
MAC1_TXD3 
BMC_GPIOS7 
BMC_GPIOS4 
BMC_GPIOS5 
BMC_GPIOS6 
BMC_GPIOZ4 
BMC_GPIOZ5 
BMC_GPIOZ6 
BMC_GPIOZ7 
MAC2_TXCTL 
MAC2_TXD0 
MAC2_TXD1 
MAC2_TXD2 
MAC2_TXD3 
NCSI_TXEN 
NCSI_TXD0 
NCSI_TXD1 
MAC1_TXD2 
MAC1_TXD3 
MAC2_TXCTL 
MAC2_TXD0 
MAC2_TXD1 
MAC2_TXD2 
MAC2_TXD3 
UART_BMC_TX 
P3V3_STBY 
P3V3_STBY 
P3V3_STBY 
P3V3_STBY 
P3V3_STBY 
BMC_SPI_CLK 21 
BMC_SPI_MOSI 21 
BMC_SPI_MISO 17,21 
NCSI_TXEN 12,21 
NCSI_TXD0 12,21 
NCSI_TXD1 12,21 
MAC1_TXD2 21 
MAC1_TXD3 21 
BMC_GPIOS6 21 
BMC_GPIOS7 21 
BMC_GPIOS4 21 
BMC_GPIOS5 21 
BMC_GPIOZ4 21 
BMC_GPIOZ5 21 
BMC_GPIOZ6 21 
BMC_GPIOZ7 21 
MAC2_TXCTL 21 
MAC2_TXD0 21 
MAC2_TXD1 21 
MAC2_TXD2 21 
MAC2_TXD3 21 
UART_BMC_TX 21,26 
Title 
Size Document Number Rev
Date: Sheet 
of 
Bryce Canyon_IO Module 2
AST2500 STRAPPING 
A3 
24 47 Friday, December 08, 2017 
Bryce Canyon_IO Module 
http://www.wiwynn.com 
8F, 90, Sec.1, Xintai 5th Rd., Xizhi Dist.,
New Taipei City 22102, Taiwan (R.O.C.)
Title 
Size Document Number Rev
Date: Sheet 
of 
Bryce Canyon_IO Module 2
AST2500 STRAPPING 
A3 
24 47 Friday, December 08, 2017 
Bryce Canyon_IO Module 
http://www.wiwynn.com 
8F, 90, Sec.1, Xintai 5th Rd., Xizhi Dist.,
New Taipei City 22102, Taiwan (R.O.C.)
Title 
Size Document Number Rev
Date: Sheet 
of 
Bryce Canyon_IO Module 2
AST2500 STRAPPING 
A3 
24 47 Friday, December 08, 2017 
Bryce Canyon_IO Module 
http://www.wiwynn.com 
8F, 90, Sec.1, Xintai 5th Rd., Xizhi Dist.,
New Taipei City 22102, Taiwan (R.O.C.)
R387 4.7k ohm 0402 1 2
R372 NOPOP 4.7k ohm 0402 1 2
R373 NOPOP 4.7k ohm 0402 1 2
R396 4.7k ohm 0402 1 2
R399 NOPOP 4.7k ohm 0402 1 2
R374 NOPOP 4.7k ohm 0402 1 2
R390 NOPOP 4.7k ohm 0402 1 2
R375 4.7k ohm 0402 1 2
R376 4.7k ohm 0402 NOPOP 1 2
R391 4.7k ohm 0402 NOPOP 1 2
R377 NOPOP 4.7k ohm 0402 1 2
R386 4.7k ohm 0402 1 2
R389 4.7k ohm 0402 NOPOP 1 2
R392 NOPOP 4.7k ohm 0402 1 2
R378 NOPOP 4.7k ohm 0402 1 2
R379 4.7k ohm 0402 1 2
R393 NOPOP 4.7k ohm 0402 1 2
R395 4.7k ohm 0402 1 2
R398 4.7k ohm 0402 1 2
R380 NOPOP 4.7k ohm 0402 1 2
R381 NOPOP 4.7k ohm 0402 1 2
R394 4.7k ohm 0402 1 2
R382 NOPOP 4.7k ohm 0402 1 2
R385 4.7k ohm 0402 1 2
R388 NOPOP 4.7k ohm 0402 1 2
R383 4.7k ohm 0402 1 2
R371 NOPOP 4.7k ohm 0402 1 2
R369 4.7k ohm 0402 1 2
R384 NOPOP 4.7k ohm 0402 1 2
R370 4.7k ohm 0402 1 2
R397 4.7k ohm 0402 1 2
R400 NOPOP 4.7k ohm 0402 1 2



5
5
4
4
3
3
2
2
1
1
D D
C C
B B
A A
P5V_STBY 
P12V_STBY 
P1V8_STBY 
P3V3_STBY 
P1V8 
P3V3 
P1V5 
P0V975 
P1V15_STBY 
P1V2_STBY 
P2V5_STBY 
ADC_P5V_STBY 22 
ADC_12V 22 
ADC_P1V8_STBY 22 
ADC_P3V3_STBY 22 
ADC_P1V8 22 
ADC_P3V3 22 
ADC_P1V5 22 
ADC_P0V975 22 
ADC_P1V15_STBY 22 
ADC_P1V2_STBY 22 
ADC_P2V5_STBY 22 
Title 
Size Document Number Rev
Date: Sheet 
of 
Bryce Canyon_IO Module 2
AST2500 VOLTAGE SENSE 
A3 
25 47Friday, December 08, 2017 
Bryce Canyon_IO Module 
http://www.wiwynn.com 
8F, 90, Sec.1, Xintai 5th Rd., Xizhi Dist.,
New Taipei City 22102, Taiwan (R.O.C.)
Title 
Size Document Number Rev
Date: Sheet 
of 
Bryce Canyon_IO Module 2
AST2500 VOLTAGE SENSE 
A3 
25 47Friday, December 08, 2017 
Bryce Canyon_IO Module 
http://www.wiwynn.com 
8F, 90, Sec.1, Xintai 5th Rd., Xizhi Dist.,
New Taipei City 22102, Taiwan (R.O.C.)
Title 
Size Document Number Rev
Date: Sheet 
of 
Bryce Canyon_IO Module 2
AST2500 VOLTAGE SENSE 
A3 
25 47Friday, December 08, 2017 
Bryce Canyon_IO Module 
http://www.wiwynn.com 
8F, 90, Sec.1, Xintai 5th Rd., Xizhi Dist.,
New Taipei City 22102, Taiwan (R.O.C.)
C122 
SCD1U25V2KX-2-GP 
0.1uF 
25V 
10% 
0402 
X7R 
1 2
R412 
1KR2F-3-GP 
1k ohm 
1/16W 
1% 
0402 
1 2
R406 
1KR2F-3-GP 
1k ohm 
1/16W 
1% 
0402 
1 2
C117 
SCD1U25V2KX-2-GP 
0.1uF 
25V 
10% 
0402 
X7R 
1 2
R401 
7K87R2F-GP 
7.87k ohm 
1/16W 
1% 
0402 
1 2
R774 
1KR2F-3-GP 
1k ohm 
1/16W 
1% 
0402 
1 2
R413 
2K7R2F-GP 
2.7k ohm 
1/16W 
1% 
0402 
1 2
C520 
SCD1U25V2KX-2-GP 
0.1uF 
25V 
10% 
0402 
X7R 
1 2
R408 
1KR2F-3-GP 
1k ohm 
1/16W 
1% 
0402 
1 2
R409 
1K4R2F-1-GP 
1.4k ohm 
1/16W 
1% 
0402 
1 2
R403 
330R2F-GP 
330 ohm 
1/16W 
1% 
0402 
1 2
C124 
SCD1U25V2KX-2-GP 
0.1uF 
25V 
10% 
0402 
X7R 
1 2
C518 
SCD1U25V2KX-2-GP 
0.1uF 
25V 
10% 
0402 
X7R 
1 2
R415 
1KR2F-3-GP 
1k ohm 
1/16W 
1% 
0402 
1 2
R775 
1KR2F-3-GP 
NOPOP 
1k ohm 
1/16W 
1% 
0402 
1 2
C118 
SCD1U25V2KX-2-GP 
0.1uF 
25V 
10% 
0402 
X7R 
1 2
C119 SCD1U25V2KX-2-GP 
0.1uF 
25V 
10% 
0402 
X7R 
1 2
C519 
SCD1U25V2KX-2-GP 
0.1uF 
25V 
10% 
0402 
X7R 
1 2
R410 
1KR2F-3-GP 
1k ohm 
1/16W 
1% 
0402 
1 2
R777 
1KR2F-3-GP 
NOPOP 
1k ohm 
1/16W 
1% 
0402 
1 2
C121 
SCD1U25V2KX-2-GP 
0.1uF 
25V 
10% 
0402 
X7R 
1 2
R405 
1KR2F-3-GP 
1k ohm 
1/16W 
1% 
0402 
1 2
R402 
330R2F-GP 
330 ohm 
1/16W 
1% 
0402 
1 2
C120 
SCD1U25V2KX-2-GP 
0.1uF 
25V 
10% 
0402 
X7R 
1 2
R779 
1KR2F-3-GP 
1k ohm 
1/16W 
1% 
0402 
1 2
R416 
1KR2F-3-GP 
NOPOP 
1k ohm 
1/16W 
1% 
0402 
1 2
R404 
1KR2F-3-GP 
1k ohm 
1/16W 
1% 
0402 
1 2
R776 
1KR2F-3-GP 
1k ohm 
1/16W 
1% 
0402 
1 2
R411 
1KR2F-3-GP 
NOPOP 
1k ohm 
1/16W 
1% 
0402 
1 2
C123 
SCD1U25V2KX-2-GP 
0.1uF 
25V 
10% 
0402 
X7R 
1 2
R414 
1KR2F-3-GP 
1k ohm 
1/16W 
1% 
0402 
1 2
R778 
866R2F-GP 
866 ohm 
1/16W 
1% 
0402 
1 2
R407 
1K4R2F-1-GP 
1.4k ohm 
1/16W 
1% 
0402 
1 2



5
5
4
4
3
3
2
2
1
1
D D
C C
B B
A A
UART_COMP_R_TX 
UART_COMP_R_RX 
PCIE_RST_R_N UART_COMP_OUT_TX 
DEBUG_UART_IOM_TX 
DEBUG_UART_IOM_RX 
UART_COMP_IN_RX 
UART_COMP_OUT_TX 
UART_BMC_RX 
UART_BMC_TX UART_SEL_MUX 
TCA9555_A2 
TCA9555_A0 
LED_POSTCODE_0 
TCA9555_A1 
I2C_DEBUG_SCL_R 
I2C_DEBUG_SDA_R 
IO_EXP0_RESET#_FLT 
DEBUG_RST_BTN_N 
DEBUG_HDR_UART_SEL 
DEBUG_UART_IOM_TX 
DEBUG_CARD_PRSNT 
UART_IOM_RX 
DEBUG_CARD_PRSNT 
DEBUG_UART_IOM_RX 
LED_POSTCODE_1 
LED_POSTCODE_2 
LED_POSTCODE_3 
LED_POSTCODE_4 
LED_POSTCODE_5 
LED_POSTCODE_6 
LED_POSTCODE_7 
DEBUG_HDR_UART_SEL 
DEBUG_GPIO_BMC_1 
DEBUG_GPIO_BMC_2 
DEBUG_GPIO_BMC_3 
DEBUG_GPIO_BMC_4 
DEBUG_GPIO_BMC_5 
DEBUG_GPIO_BMC_6 
UART_COMP_IN_RX 
UART_BMC_COMP_IN_RX_R 
UART_COMP_IN_RX_AND 
UART_COMP_IN_R_RX 
UART_COMP_IN_RX_AND UART_COMP_IN_RX_AND_R 
UART_SDB_TX_R 
UART_EXP_BMC_TX 
UART_EXP_BMC_RX 
UART_SDB_RX 
EXP_UART_EN_R 
UART_COMP_IN_RX 
I2C_DEBUG_SDA_L 
DEBUG_CARD_PRSNT 
I2C_DEBUG_SCL_L 
DEBUG_CARD_PRSNT 
DEBUG_UART_IOM_RX 
TCA9555_A2 
TCA9555_A0 
TCA9555_A1 
D_FLIP_Q# 
UART_SEL_MUX 
D_FLIP_Q 
D_FLIP_Q# 
BMC_UART_SEL_IN DEBUG_HDR_UART_SEL 
DEBUG_HDR_UART_SEL 
D_FLIP_PRE# D_FLIP_D 
DEBUG_HDR_UART_SEL 
D_FLIP_Q 
D_FLIP_CLR# 
P3V3_STBY 
P3V3_STBY 
P3V3_STBY 
P3V3_STBY 
P3V3_STBY 
P3V3_STBY 
P3V3_STBY 
P3V3_STBY 
P3V3_STBY 
P3V3_STBY 
P3V3_STBY P3V3_STBY 
P3V3_STBY 
P3V3_STBY 
P3V3_STBY 
P3V3_STBY 
UART_COMP_TX 11 
UART_COMP_RX 11 
PCIE_COMP_TO_IOM_RST_4 11,12,14,21 UART_COMP_OUT_TX 21 
UART_BMC_TX 21,24
UART_BMC_RX 21 
I2C_DEBUG_SCL_L 20 
I2C_DEBUG_SDA_L 20 
DEBUG_RST_BTN_N 21,22 
BMC_UART_SEL_OUT 21 
LED_POSTCODE_0 21 
DB_PRSNT_BMC_N 20
DEBUG_CARD_PRSNT 14 
UART_IOM_TX 14 
UART_IOM_RX 14 
LED_POSTCODE_1 21 
LED_POSTCODE_2 21 
LED_POSTCODE_3 21 
LED_POSTCODE_4 21 
LED_POSTCODE_5 21 
LED_POSTCODE_6 21 
LED_POSTCODE_7 21 
DEBUG_GPIO_BMC_1 22 
DEBUG_GPIO_BMC_2 22 
DEBUG_GPIO_BMC_3 22 
DEBUG_GPIO_BMC_4 22 
DEBUG_GPIO_BMC_5 22 
DEBUG_GPIO_BMC_6 22 
UART_BMC_COMP_IN_RX 21 
UART_SDB_TX 11 
UART_EXP_BMC_TX 21 
UART_EXP_BMC_RX 21 
UART_SDB_RX 11 
EXP_UART_EN 21 
I2C_DEBUG_SDA 14 
I2C_DEBUG_SCL 14 
BMC_UART_SEL_IN 21 
Title 
Size Document Number Rev
Date: Sheet 
of 
Bryce Canyon_IO Module 2
DEBUG PORT 
A3 
26 47 Friday, December 08, 2017 
Bryce Canyon_IO Module 
http://www.wiwynn.com 
8F, 90, Sec.1, Xintai 5th Rd., Xizhi Dist.,
New Taipei City 22102, Taiwan (R.O.C.)
Title 
Size Document Number Rev
Date: Sheet 
of 
Bryce Canyon_IO Module 2
DEBUG PORT 
A3 
26 47 Friday, December 08, 2017 
Bryce Canyon_IO Module 
http://www.wiwynn.com 
8F, 90, Sec.1, Xintai 5th Rd., Xizhi Dist.,
New Taipei City 22102, Taiwan (R.O.C.)
Title 
Size Document Number Rev
Date: Sheet 
of 
Bryce Canyon_IO Module 2
DEBUG PORT 
A3 
26 47 Friday, December 08, 2017 
Bryce Canyon_IO Module 
http://www.wiwynn.com 
8F, 90, Sec.1, Xintai 5th Rd., Xizhi Dist.,
New Taipei City 22102, Taiwan (R.O.C.)
U32 
SN74LVC126APWR-1-GP 
1OE 1
1A 2 1Y 3
2OE 4
2A 5 2Y 6
GND 7
3Y 8
3A 9 3OE 10 
4Y 11 
4A 12 4OE 13 
VCC 14 
R422 
4K7R2F-GP 
4.7k ohm 
1/16W 
1% 
0402 
1 2
R423 
4K7R2F-GP 
4.7k ohm 
1/16W 
1% 
0402 
1 2
U33 
TS5A23157DGSR-GP 
IN1 1
NO1 2
GND 3
NO2 4IN2 5
COM2 6
NC2 7V+ 8 NC1 9
COM1 10 
C125 
SCD1U25V2KX-2-GP 
0.1uF 
25V 
10% 
0402 
X7R 
1 2
R424 
4K7R2F-GP 
4.7k ohm 
1/16W 
1% 
0402 
1 2
R418 0 ohm 0402 12
C485 
SCD1U16V2KX-3GP 
0.1uF 
16V 
10% 
0402 
X7R 
1 2
R417 0 ohm 0402 12
U101 
SNLVC1G126DCKR-GP 
OE 1
A2
GND 3 Y 4
VCC 5
R420 
4K7R2F-GP 
4.7k ohm 
1/16W 
1% 
0402 
1 2
R722 
10KR2J-3-GP 
10k ohm 
1/16W 
5% 
0402 
12
R797 0 ohm 0402 12
R796 0 ohm 0402 12
R105 
4K7R2F-GP 
4.7k ohm 
1/16W 
1% 
0402 
1 2
Q26 
2N7002K-1-GP 
G
D S
C40 
SCD1U16V2KX-3GP 
0.1uF 
16V 
10% 
0402 
X7R 
NOPOP 
1 2
U45 
PCA9306DCTT-GP 
GND 1
VREF1 2
SCL1 3
SDA1 4 SDA2 5
SCL2 6
VREF2 7
EN 8
R452 0 ohm 0402 12
C513 
SCD1U16V2KX-3GP
0.1uF 
16V 
10% 
0402 
X7R 
1 2
R430 
4K7R2F-GP 
NOPOP 
4.7k ohm 
1/16W 
1% 
0402 
1 2
R715 0 ohm 0402 12
C32 
SCD1U16V2KX-3GP 
0.1uF 
16V 
10% 
0402 
X7R 
NOPOP 
1 2
R419 0 ohm 0402 12
R721 
4K7R2F-GP 
4.7k ohm 
1/16W 
1% 
0402 
1 2
U34 
TCA9555PWR-GP 
INT# 1
A1 2
A2 3
P00 4
P01 5
P02 6
P03 7
P04 8
P05 9
P06 10 
P07 11 GND 12 
VCC 24 
SDA 23 
SCL 22 A0 21 
P10 13 
P11 14 
P12 15 
P13 16 
P14 17 
P15 18 
P16 19 
P17 20 
R688 
100KR2F-L1-GP 
100k ohm 
1/16W 
1% 
0402 
1 2
C503 
SCD1U16V2KX-3GP 
0.1uF 
16V 
10% 
0402 
X7R 
1 2
C504 
SCD1U16V2KX-3GP 
0.1uF 
16V 
10% 
0402 
X7R 
1 2
R426 0 ohm 0402 12
U46 
SN74LVC1G08DCKR-GP 
B 2
A 1
GND 3Y4
VCC 5
U100 
SNLVC1G126DCKR-GP 
OE 1
A2
GND 3 Y 4
VCC 5
R429 
4K7R2F-GP 
NOPOP 
4.7k ohm 
1/16W 
1% 
0402 
1 2
R725 
4K7R2F-GP 
4.7k ohm 
1/16W 
1% 
0402 
1 2
R795 0 ohm 0402 12
R54 
0R2J-2-GP 
0 ohm 
1/16W 
5% 
0402 
1 2
C126 
SCD1U16V2KX-3GP 
0.1uF 
16V 
10% 
0402 
X7R 
1 2
R421 
10KR2F-2-GP 
NOPOP 
10k ohm 
1/16W 1% 
0402 
1 2
C522 
SCD1U25V2KX-2-GP 
1 2
R275 
100KR2F-L1-GP 
100k ohm 
1/16W 
1% 
0402 
1 2
R425 
4K7R2F-GP 
4.7k ohm 
1/16W 
1% 
0402 
1 2
R99 
0R2J-2-GP 
0 ohm 
1/16W 
5% 
0402 
1 2
R428 
4K7R2F-GP 
NOPOP 
4.7k ohm 
1/16W 
1% 
0402 
1 2
R738 
4K7R2F-GP 
4.7k ohm 
1/16W 
1% 
0402 
1 2
C137 
SCD1U16V2KX-3GP 
0.1uF 
16V 
10% 
0402 
X7R 
NOPOP 
1 2
R427 0 ohm 0402 12
R102 0R2J-2-GP 
0 ohm 1/16W 5% 0402 
NOPOP 12
R651 0 ohm 0402 12
C127 
SCD1U16V2KX-3GP 
0.1uF 
16V 
10% 
0402 
X7R 
1 2
C30 
SCD1U16V2KX-3GP 
0.1uF 
16V 
10% 
0402 
X7R 
1 2
R451 
10KR2F-2-GP 
NOPOP 
10k ohm 
1/16W 1% 
0402 
1 2
R95 0R2J-2-GP 
0 ohm 1/16W 5% 0402 
NOPOP 12
R98 0R2J-2-GP 
0 ohm 1/16W 5% 0402 
12
U19 
SN74LVC1G74DCUT-GP 
CLK 1
D2
Q# 3
GND 4 Q 5CLR# 6PRE# 7VCC 8



5
5
4
4
3
3
2
2
1
1
D D
C C
B B
A A
Controller : ADM1278 
TDC :6.15A 
OCP :9.12A 
MB0_TEMP_C 
MB0_P12V_PWGIN_R 
MB0_CM_GATE_R 
MB0_CM_ADR1_R 
MB0_TEMP 
P12V_IOM_PGOOD 
MB0_SPISS_PD 
MB0_CM_SENSE_R1_P 
P12V_IOM_PGOOD 
MB0_VCAP_R MB0_ISET_R 
MB0_SPISS_PD 
MB0_CM_ADR2_R 
MB0_CM_SENSE_R1_N 
MB0_CM_VOUT_R 
MB0_CM_GATE 
MB0_12V_CTRL_GATE1 
MB0_CM_UV_R 
MB0_VCAP_R 
MB0_CM_ADR1_R MB0_CM_ADR2_R 
MB0_VCAP_R 
MB0_CM_SENSE_R1_N 
MB0_CM_SENSE_P MB0_CM_SENSE_R1_P 
MB0_CM_SENSE_N 
MB0_P12V_PWGIN_R 
MB0_RETRY_R 
MB0_HS_ENABLE 
HSW_SCL 
HSW_SDA 
ADM1278_HS_N 
ADM1278_HS_P 
MB0_TIME_R 
MB0_ISET_R 
MB0_PSET_R 
MB0_CM_SENSE_P 
MB0_CM_SENSE_N 
MB0_CM_VOUT_R 
MB0_VCC 
MB0_VCAP_R 
MB0_CM_OV_R 
MB0_ISTART_R 
MB0_CM_UV_R 
MB0_RETRY_R 
MB0_TEMP_E 
MB0_TEMP 
MB0_CM_OV_R 
MB0_CM_SENSE_R1_N 
ADM1278_HS_P MB0_CM_SENSE_R1_P 
ADM1278_HS_N 
MB0_TIME_R 
MB0_CM_VOUT_R 
MB0_PSET_R 
MB0_ISTART_R 
MB0_CM_GATE_2 
MB0_CM_GATE 
IOM_ADM1278_EN 
IOM_MATED_N 
IOM_ADM1278_EN 
P12V_IOM 
P12V_STBY 
MB0_P12V_MAIN_R 
AGND_CURRENT_MON 
AGND_CURRENT_MON 
AGND_CURRENT_MON 
AGND_CURRENT_MON 
AGND_CURRENT_MON 
AGND_CURRENT_MON 
AGND_CURRENT_MON 
P12V_STBY 
AGND_CURRENT_MON 
AGND_CURRENT_MON 
AGND_CURRENT_MON AGND_CURRENT_MON 
P12V_STBY 
P12V_IOM 
AGND_CURRENT_MON 
P12V_IOM 
AGND_CURRENT_MON 
AGND_CURRENT_MON 
AGND_CURRENT_MON 
AGND_CURRENT_MON 
AGND_CURRENT_MON 
P12V_IOM 
P12V_IOM 
I2C_IOM_SDA 19,20 
P12V_IOM_PGOOD 28 
I2C_IOM_SCL 19,20 
P12V_A_PGOOD 11,21 
IOM_MATED_N 11 
Title 
Size Document Number Rev 
Date: Sheet 
of 
Bryce Canyon_IO Module 2
HOT SWAP CONTROLLER ADM1278 
C
27 47 Friday, December 08, 2017 
Bryce Canyon_IO Module 
http://www.wiwynn.com 
8F, 90, Sec.1, Xintai 5th Rd., Xizhi Dist., 
New Taipei City 22102, Taiwan (R.O.C.) 
Title 
Size Document Number Rev 
Date: Sheet 
of 
Bryce Canyon_IO Module 2
HOT SWAP CONTROLLER ADM1278 
C
27 47 Friday, December 08, 2017 
Bryce Canyon_IO Module 
http://www.wiwynn.com 
8F, 90, Sec.1, Xintai 5th Rd., Xizhi Dist., 
New Taipei City 22102, Taiwan (R.O.C.) 
Title 
Size Document Number Rev 
Date: Sheet 
of 
Bryce Canyon_IO Module 2
HOT SWAP CONTROLLER ADM1278 
C
27 47 Friday, December 08, 2017 
Bryce Canyon_IO Module 
http://www.wiwynn.com 
8F, 90, Sec.1, Xintai 5th Rd., Xizhi Dist., 
New Taipei City 22102, Taiwan (R.O.C.) 
R455 
1MR3J-L-GP 
NOPOP 
1M ohm 
1/10W 
5% 
0603 
1 2
R743 
100KR2F-L1-GP 
100k ohm 
1/16W 
1% 
0402 
1 2
R431 10R2F-L-GP 
10 ohm 1/16W 1% 0402 
1 2
R433 
10KR2F-2-GP 
10k ohm 
1/16W 
1% 
0402 
1 2
R712 0 ohm 0402 12
C139 
SCD1U50V3KX-GP 
0.1uF 
50V 
10% 
0603 
X7R 
1 2
C150 
SCD1U50V3KX-GP 
0.1uF 
50V 
10% 
0603 
X7R 
1 2
R454 51KR2F-L-GP 
51k ohm 
1/16W 
1% 
0402 
1 2
R460 
0R2J-2-GP 
0 ohm 
1/16W 
5% 
0402 
1 2
C130 
SCD1U16V2KX-3GP 
0.1uF 
16V 
10% 
0402 
X7R 
1 2
R445 
49K9R2F-L-GP 
49.9k ohm 
1/16W 
1% 
0402 
1 2
R457 100KR2J-4-GP 
100k ohm 1/16W 5% 0402 
1 2
R443 10R2F-L-GP 
10 ohm 1/16W 1% 0402 
12
C145 
SC1U16V3KX-5GP 
1uF 
16V 
10% 
0603 
X7R 
1 2
R462 22K6R2F-1-GP 
22.6k ohm 1/16W 1% 0402 
1 2R461 100KR2J-4-GP 
100k ohm 1/16W 5% 0402 
1 2
R741 0 ohm 0402 
NOPOP 
12
C148 
SCD1U50V3KX-GP 
0.1uF 
50V 
10% 
0603 
X7R 
1 2
C131 
SCD01U25V2KX-3GP 
0.01uF 
25V 
10% 
0402 
X7R 
1 2
C144 
SC1U16V3KX-5GP 
1uF 
16V 
10% 
0603 
X7R 
1 2 R450 
10R5F-1-GP 
10 ohm 
1/8W 
1% 
0805 
1 2
R441 10R2F-L-GP 
10 ohm 1/16W 1% 0402 
12
C138 
SCD1U25V2KX-2-GP 
0.1uF 
25V 
10% 
0402 
X7R 
1 2
R438 
10KR2J-3-GP 
NOPOP 
10k ohm 
1/16W 
5% 
0402 
12
R434 100R2D-GP 
100 ohm 1/16W No Tolerance 0402 
1 2
C132 
SC22UF16V6KX-GP 
22uF 
16V 
10% 
1206 
X6S 
1 2
R744 
11KR2F-L-GP 
11k ohm 
1/16W 
1% 
0402 
1 2
R710 0R5J-5-GP 
0 ohm 1/8W 5% 0805 
12
C133 
SCD015U25V2KX-GP 
0.015uF 
25V 
10% 
0402 
X7R 
1 2
C146 
SCD033U50V3KX-1GP 
0.033uF 
50V 
10% 
0603 
X7R 
1 2
R711 0 ohm 0402 12
C149 
SCD1U50V3KX-GP 
0.1uF 
50V 
10% 
0603 
X7R 
1 2
D
S
G
Q5 
PSMN0R9-25YLC-GP 
5
4
1
2
3
R444 
D002RL3115F-L-GP 
0.002 ohm 
1W 1% 0612 
12
34
R742 
10KR2F-2-GP 
10k ohm 
1/16W 
1% 
0402 
1 2
R447 
4K12R2F-3-GP 
4.12k ohm 
1/16W 
1% 
0402 
1 2
P1 0R0603-PAD-2-GP-U 1 2
PQ1 
MMBT3904-3-GP 
C
B
E
R453 100KR2J-4-GP 
100k ohm 
1/16W 
5% 
0402 
1 2
R432 100R2D-GP 
100 ohm 1/16W No Tolerance 0402 
1 2
R440 10R2F-L-GP 
10 ohm 1/16W 1% 0402 
12
R437 
100KR2F-L1-GP 
100k ohm 
1/16W 
1% 
0402 
1 2
D1 
SMF15A-GP 
AK
CA1 
SC2D2U25V5KX-2-GP 
NOPOP 
2.2uF 
25V 
10% 
0805 
X7R 
1 2
C134 
SCD015U25V2KX-GP 
NOPOP 
0.015uF 
25V 
10% 
0402 
X7R 
1 2
R446 
49K9R2F-L-GP 
49.9k ohm 
1/16W 
1% 
0402 
1 2
R448 
5K1R2F-3-GP 
5.1k ohm 
1/16W 
1% 
0402 
1 2
R449 1KR2J-1-GP 
1k ohm 1/16W 5% 0402 
1 2
R442 10R2F-L-GP 
10 ohm 1/16W 1% 0402 
12
C147 
SC1U16V3KX-5GP 
1uF 
16V 
10% 
0603 
X7R 
1 2
R456 
0R2J-2-GP 
NOPOP 
0 ohm 
1/16W 
5% 
0402 
1 2
C128 
SC1U25V3KX-GP 
1uF 
25V 
10% 
0603 
X7R 
1 2
R439 
11KR2F-L-GP 
11k ohm 
1/16W 
1% 
0402 
1 2
R459 
0R2J-2-GP 
0 ohm 
1/16W 
5% 
0402 
1 2
R709 
0R5J-5-GP 
0 ohm 
1/8W 
5% 
0805 
12
R436 0 ohm 0402 12
Q20 
2N7002K-1-GP G
D S
U35 
ADM1278-2ACPZ-RL-1-GP 
VCAP 2 MCLK 10 MDAT 11 
GPO2/ALERT2# 14 
VOUT 20 
GND 22 
PGND 23 
VCC 30 
UV 31 
OV 32 
GND 33 
ISTART 4
TIMER 5
RETRY# 17 
MO- 26 
MO+ 29 
HS- 27 
HS+ 28 
GPO1/ALERT1#/CONV 13 
PSET 1
ISET 3
ADR1 7
ADR2 8
SCL 16 
SDA 15 
GATE 24 
TEMP 25 
FAULT# 6
SPISS# 9
ENABLE 12 
CSOUT 19 PWGIN 21 
PWRGD 18 
R458 86K6R2F-GP 
86.6k ohm 1/16W 1% 0402 
1 2
R435 
3K83R2F-GP 
3.83k ohm 
1/16W 
1% 
0402 
1 2
C129 
SC1KP50V2KX-1GP 
1000pF 
50V 
10% 
0402 
X7R 
1 2



5
5
4
4
3
3
2
2
1
1
D D
C C
B B
A A
Power rail : P5V_STBY 
Controller : TPS53318 (Fswitching=500KHz) 
TDC : 3.4A 
MAX : 3.4A 
OCP : 5.1A 
P5V_EN_R 
P5V_RF 
P5V_STBY_VREG 
P5V_STBY_VREG 
P5V_LL_R 
P5V_VBST_RC 
P12V_STBY_VDD_PU1 
P5V_SNB 
P5V_VFB 
PWRGD_P5V_STBY 
P5V_CC 
P12V_STBY_VIN_PU1 
P5V_VBST 
P5V_MODE 
P5V_TRIP 
P5V_VFB_R 
P5V_LL P5V_STBY_VREG 
P12V_STBY 
P12V_STBY 
P5V_STBY 
AGND_P5V 
AGND_P5V 
AGND_P5V 
AGND_P5V 
AGND_P5V 
P12V_STBY 
AGND_P5V 
P5V_STBY 
PWRGD_P5V_STBY 29 
P12V_IOM_PGOOD 27 
Title 
Size Document Number Rev
Date: Sheet 
of 
Bryce Canyon_IO Module 2A3 
28 47 Friday, December 08, 2017 
Bryce Canyon_IO Module 
http://www.wiwynn.com 
8F, 90, Sec.1, Xintai 5th Rd., Xizhi Dist.,
New Taipei, Taiwan 
PWRSW_P5V_STBY_TPS53319 
Title 
Size Document Number Rev
Date: Sheet 
of 
Bryce Canyon_IO Module 2A3 
28 47 Friday, December 08, 2017 
Bryce Canyon_IO Module 
http://www.wiwynn.com 
8F, 90, Sec.1, Xintai 5th Rd., Xizhi Dist.,
New Taipei, Taiwan 
PWRSW_P5V_STBY_TPS53319 
Title 
Size Document Number Rev
Date: Sheet 
of 
Bryce Canyon_IO Module 2A3 
28 47 Friday, December 08, 2017 
Bryce Canyon_IO Module 
http://www.wiwynn.com 
8F, 90, Sec.1, Xintai 5th Rd., Xizhi Dist.,
New Taipei, Taiwan 
PWRSW_P5V_STBY_TPS53319 
R465 
2K2R2F-GP 
NOPOP 
2.2k ohm 
1/16W 
1% 
0402 
1 2
L7 
IND-4D7UH-291-GP 
4.7uH 
Isat=15A 
Idc=8A 
DCR=20mOhm 
Tmax=125C 
1 2
R713 0 ohm 0402 12
R478 
10KR2F-2-GP 
10k ohm 
1/16W 
1% 
0402 
1 2
C165 
SC10U16V5KX-7-GP-U 
10uF 
16V 
10% 
0805 
X7R 
1 2
C155 
SC10U16V5KX-7-GP-U 
10uF 
16V 
10% 
0805 
X7R 
1 2
R471 
15KR2F-GP 
15k ohm 
1/16W 
1% 
0402 
1 2
R464 
2D2R3-1-U-GP 
2.2 ohm 
1/10W 
1% 
0603 
1 2
C162 
SC1KP50V2KX-1GP 
1000pF 
50V 
10% 
0402 
X7R 
1 2
R466 
2D7R3-GP 
2.7 ohm 1/10W 5% 0603 
1 2
C166 
SC10U16V5KX-7-GP-U 
10uF 
16V 
10% 
0805 
X7R 
1 2
R467 
10KR2F-2-GP 
10k ohm 
1/16W 
1% 
0402 
1 2
C154 
SC10U16V5KX-7-GP-U 
10uF 
16V 
10% 
0805 
X7R 
1 2
PU1 
TPS53318DQPR-GP 
74.53318.073 
VFB 1PGOOD 3
EN 2
VBST 4
ROVP 5
LL#6 6
LL#7 7
LL#8 8
LL#9 9
LL#10 10 
LL#11 11 
VIN 12 VIN 13 VIN 14 VIN 15 VIN 16 VIN 17 
VREG 18 
VDD 19 
MODE 20 
TRIP 21 
RF 22 
GND 23 
R472 100KR2F-L1-GP NOPOP 
100k ohm 1/16W 1% 0402 
1 2
R469 
3D01R5F-GP 
NOPOP 
3.01 ohm 
1/8W 
1% 
0805 
1 2
C168 
ST150U16VDM-3-GP 
150uF 
16V 
Irp=1.8A 
ESR= 55mOhm 
Tmax=105C 
1 2
C151 
SC10U16V5KX-7-GP-U 
10uF 
16V 
10% 
0805 
X7R 
1 2
C156 
SC1U16V3KX-5GP 
1uF 
16V 
10% 
0603 
X7R 
1 2
C163 SC68P50V2JN-2-GP 
68pF 50V 5% 0402 NPO 
NOPOP 
1 2
R473 
10R3F-GP 
10 ohm 
1/10W 
1% 
0603 
1 2
C160 
SCD1U50V3KX-GP 
0.1uF 
50V 
10% 
0603 
X7R 
1 2
C157 
SC4D7U25V5KX-1-GP 
4.7uF 
25V 
10% 
0805 
X7R 
1 2
R474 73K2R2F-GP 
73.2k ohm 1/16W 1% 0402 
1 2
C161 SC1U16V3KX-5GP 
1uF 16V 10% 0603X7R 
1 2
G1 
GAP-CLOSE-PWR-4-GP
1 2
G2 
COPPER-CLOSE-GP-U 
1 2
L6 
BLM21PG220SN1DGP 
22Ohm@100MHz 
Imax=6A 
DCR=20mOhm 
Tmax=125C 
1 2
C159 
SC2200P50V2KX-2GP 
2200pF 
50V 
10% 
0402 
X7R 
NOPOP 
1 2
R475 57K6R2D-GP 
57.6k ohm 1/16W No Tolerance 0402 
1 2
C152 
SC10U16V5KX-7-GP-U 
10uF 
16V 
10% 
0805 
X7R 
1 2
C158 
SCD1U50V3KX-GP 
0.1uF 
50V 
10% 
0603 
X7R 
1 2
R468 
3K3R2J-3-GP 
3.3k ohm 
1/16W 
5% 
0402 
1 2
C167 
ST100U16VDM-3-GP 
100uF 
16V 
Irp=1.5A 
ESR= 50mOhm 
Tmax=105C 
1 2
R463 
10KR2F-2-GP 
NOPOP 
10k ohm 
1/16W 
1% 
0402 
1 2
R477 
619KR2F-GP 
NOPOP 
619k ohm 
1/16W 1% 
0402 
1 2
R476 866KR2F-GP NOPOP 
866k ohm 1/16W 1% 0402 
1 2
C164 
SC10U16V5KX-7-GP-U 
10uF 
16V 
10% 
0805 
X7R 
1 2
R470 200KR2F-L-GP 
200k ohm 1/16W 1% 0402 
1 2
C153 
SC10U16V5KX-7-GP-U 
10uF 
16V 
10% 
0805 
X7R 
1 2



5
5
4
4
3
3
2
2
1
1
D D
C C
B B
A A
Power rail : P3V3_STBY 
Controller : TPS53318 (Fswitching=500KHz) 
TDC : 3A 
MAX : 3A 
OCP : 5.3A 
P3V3_STBY_VFB_R 
P3V3_STBY_ROVP 
P3V3_VBST 
P12V_STBY_VIN_PU2 
P3V3_STBY_VREG 
P3V3_STBY_LL 
P3V3_STBY_EN 
P3V3_STBY_RF 
P3V3_STBY_VREG 
P3V3_STBY_TRIP 
P3V3_STBY_MODE 
P3V3_STBY_OUT 
P3V3_VBST_RC 
P12V_STBY_VDD_PU2 
P3V3_SNB 
P3V3_STBY_VFB 
P3V3_STBY_LL_R 
P3V3_STBY_OUT 
PQ2_G 
PQ2_D 
IOM_STBY_PGOOD 
P3V3_EN 
IOM_FULL_PWR_EN 
IOM_FULL_PWR_EN 
P3V3_EN_R P3V3_EN 
P12V_STBY 
AGND_P3V3_STBY 
AGND_P3V3_STBY 
AGND_P3V3_STBY 
AGND_P3V3_STBY 
P12V_STBY 
AGND_P3V3_STBY 
P3V3_STBY_VREG 
P12V_STBY 
P3V3_STBY 
P3V3 
P3V3_STBY 
P12V_STBY 
P3V3_STBY 
P3V3_STBY 
P3V3_STBY 
PWRGD_P3V3_STBY 18,30 
PWRGD_P5V_STBY 28 
IOM_FULL_PWR_EN 21 
IOM_STBY_PGOOD 22,33 
Title 
Size Document Number Rev
Date: Sheet 
of 
Bryce Canyon_IO Module 2
PWRSW_P3V3_STBY_TPS53318 
A3 
29 47 Friday, December 08, 2017 
Bryce Canyon_IO Module 
http://www.wiwynn.com 
8F, 90, Sec.1, Xintai 5th Rd., Xizhi Dist.,
New Taipei City 22102, Taiwan (R.O.C.)
Title 
Size Document Number Rev
Date: Sheet 
of 
Bryce Canyon_IO Module 2
PWRSW_P3V3_STBY_TPS53318 
A3 
29 47 Friday, December 08, 2017 
Bryce Canyon_IO Module 
http://www.wiwynn.com 
8F, 90, Sec.1, Xintai 5th Rd., Xizhi Dist.,
New Taipei City 22102, Taiwan (R.O.C.)
Title 
Size Document Number Rev
Date: Sheet 
of 
Bryce Canyon_IO Module 2
PWRSW_P3V3_STBY_TPS53318 
A3 
29 47 Friday, December 08, 2017 
Bryce Canyon_IO Module 
http://www.wiwynn.com 
8F, 90, Sec.1, Xintai 5th Rd., Xizhi Dist.,
New Taipei City 22102, Taiwan (R.O.C.)
D4 
SMF15A-GP 
NOPOP 
AK
C174 
SC10U6D3V5KX-4GP 
10uF 
6.3V 
10% 
0805 
X7R 
1 2
R498 
0R2J-2-GP 
0 ohm 
1/16W 
5% 
0402 
1 2
R488 
2K7R2F-GP 
2.7k ohm 
1/16W 
1% 0402 
1 2
S
S
S
G D
D
D
D
PQ3 
FDS8878-G-GP 
1
2
3
45
6
7
8
C176 
SC10U16V5KX-7-GP-U 
10uF 
16V 
10% 
0805 
X7R 
1 2
C172 
SC10U6D3V5KX-4GP 
10uF 
6.3V 
10% 
0805 
X7R 
1 2
R719 0 ohm 0402 12
R495 866KR2F-GP NOPOP 
866k ohm 1/16W 1% 0402 
1 2
C171 
SC10U16V5KX-7-GP-U 
10uF 
16V 
10% 
0805 
X7R 
1 2
G3 
COPPER-CLOSE-GP-U 
1 2
C188 
SC10U6D3V5KX-4GP 
10uF 
6.3V 
10% 
0805 
X7R 
1 2
R496 44K2R2F-1-GP 
44.2k ohm 1/16W 1% 0402 
1 2
PU2 
TPS53318DQPR-GP 
74.53318.073 
VFB 1PGOOD 3
EN 2
VBST 4
ROVP 5
LL#6 6
LL#7 7
LL#8 8
LL#9 9
LL#10 10 
LL#11 11 
VIN 12 VIN 13 VIN 14 VIN 15 VIN 16 VIN 17 
VREG 18 
VDD 19 
MODE 20 
TRIP 21 
RF 22 
GND 23 
C173 
SC10U16V5KX-7-GP-U 
10uF 
16V 
10% 
0805 
X7R 
1 2
R497 619KR2F-GP NOPOP 
619k ohm 1/16W 1% 0402 
1 2
R482 
10KR2J-3-GP 
NOPOP 10k ohm 
1/16W 
5% 
0402 
1 2
R494 57K6R2D-GP 
57.6k ohm 1/16W No Tolerance 0402 
1 2
C178 
SCD1U50V3KX-GP 
0.1uF 
50V 
10% 
0603 
X7R 
1 2
C177 
SC10U16V5KX-7-GP-U 
10uF 
16V 
10% 
0805 
X7R 
1 2
C186 
SCD47U25V3KX-3-GP 
0.47uF 
25V 
10% 
0603 
X7R 
1 2
C170 
SC10U16V5KX-7-GP-U 
10uF 
16V 
10% 
0805 
X7R 
1 2
R491 
15KR2F-GP 
15k ohm 
1/16W 
1% 
0402 
1 2
R484 3D01R5F-GP 
3.01 ohm 
1/8W 
1% 
0805 
1 2
C180 
SC2200P50V2KX-2GP 
2200pF 
50V 
10% 
0402 
X7R 
NOPOP 
1 2
R489 
10R3F-GP 
10 ohm 
1/10W 
1% 
0603 
1 2
L8 
BLM21PG220SN1DGP 
22Ohm@100MHz 
Imax=6A 
DCR=20mOhm 
Tmax=125C 
1 2
C175 
ST150U6D3VDM-28-GP 
150uF 
6.3V 
Irp=2.5A 
ESR= 17mOhm 
Tmax=105C 
1 2
C184 SC68P50V2JN-2-GP 
68pF 50V 5% 0402 NPO 
NOPOP 
1 2
R500 
2K2R2J-2-GP 
2.2k ohm 
1/16W 
5% 
0402 
1 2
R502 
1MR2F-GP 
1M ohm 
1/16W 
1% 
0402 
12
U36 
SN74LVC1G08DCKR-GP 
B2
A1
GND 3 Y 4
VCC 5
R487 
10KR2F-2-GP 
10k ohm 
1/16W 
1% 
0402 
1 2
R493 100KR2F-L1-GP NOPOP 
100k ohm 1/16W 1% 0402 
1 2
C169 
SCD1U16V2KX-3GP 
0.1uF 
16V 
10% 
0402 
X7R 
1 2
C189 
SCD1U25V2KX-2-GP
0.1uF 
25V 
10% 
0402 
X7R 
1 2
R483 
2D2R3J-2-GP 
2.2 ohm 
1/10W 
5% 
0603 
12
C182 SC1U16V3KX-5GP 
1uF 16V 10% 0603X7R 
1 2
R492 475KR2F-GP 
475k ohm 1/16W 1% 0402 
1 2
C187 
SC10U6D3V5KX-4GP 
10uF 
6.3V 
10% 
0805 
X7R 
1 2
R490 
3D01R5F-GP 
NOPOP 
3.01 ohm 
1/8W 
1% 
0805 
1 2
L9 
COIL-3D3UH-26-GP 
3.3uH 
Isat=9.5A 
Idc=6.5A 
DCR=18mOhm 
Tmax=125C 
1 2
R485 0 ohm 0402 12
R481 
0R6J-3-GP 
0 ohm 
1/4W 
5% 
1206 
1 2
C507 
SCD1U16V2KX-3GP 
0.1uF 
16V 
10% 
0402 
X7R 
NOPOP 
1 2
C183 
SC1KP50V2KX-1GP 
1000pF 
50V 
10% 
0402 
X7R 
1 2
PQ2 
2N7002K-1-GP 
G
DS
C181 
SCD1U25V2KX-2-GP 
0.1uF 
25V 
10% 
0402 
X7R 
1 2
R499 
10KR2F-2-GP 
10k ohm 
1/16W 
1% 
0402 
1 2
R503 
1KR2F-3-GP 
1k ohm 
1/16W 
1% 
0402 
1 2
R486 
3K83R2F-GP 
NOPOP 
3.83k ohm 
1/16W 
1% 
0402 
1 2
R704 
100KR2J-4-GP 
100k ohm 
1/16W 
5% 
0402 
NOPOP 
12
C185 
SCD1U16V2KX-3GP 
0.1uF 
16V 
10% 
0402 
X7R 
1 2
R501 
2K2R2J-2-GP 
2.2k ohm 
1/16W 
5% 
0402 
1 2
R480 
0R6J-3-GP 
0 ohm 
1/4W 
5% 
1206 
1 2
R479 
0R6J-3-GP 
0 ohm 
1/4W 
5% 
1206 
1 2
C179 
SC4D7U25V5KX-1-GP 
4.7uF 
25V 
10% 
0805 
X7R 
1 2



5
5
4
4
3
3
2
2
1
1
D D
C C
B B
A A
Power rail :P2V5_STBY(2.5V) 
Controller :TPS74801 
TDC :0.2A 
Max :0.2A 
OCP:2A 
TPS74801_P2V5_STBY_OUT 
TPS74801_P2V5_STBY_EN 
TPS74801_P2V5_STBY_SS 
TPS74801_P2V5_STBY_BIAS 
TPS74801_P2V5_STBY_FB 
P3V3_STBY 
P2V5_STBY 
P3V3_STBY 
P5V_STBY 
P3V3_STBY 
PWRGD_P3V3_STBY 18,29 
PWRGD_P2V5_STBY 31 
Title 
Size Document Number Rev
Date: Sheet 
of 
Bryce Canyon_IO Module 2
PWRLDO_P2V5_STBY_TPS74801 
A3 
30 47 Friday, December 08, 2017 
Bryce Canyon_IO Module 
http://www.wiwynn.com 
8F, 90, Sec.1, Xintai 5th Rd., Xizhi Dist.,
New Taipei City 22102, Taiwan (R.O.C.)
Title 
Size Document Number Rev
Date: Sheet 
of 
Bryce Canyon_IO Module 2
PWRLDO_P2V5_STBY_TPS74801 
A3 
30 47 Friday, December 08, 2017 
Bryce Canyon_IO Module 
http://www.wiwynn.com 
8F, 90, Sec.1, Xintai 5th Rd., Xizhi Dist.,
New Taipei City 22102, Taiwan (R.O.C.)
Title 
Size Document Number Rev
Date: Sheet 
of 
Bryce Canyon_IO Module 2
PWRLDO_P2V5_STBY_TPS74801 
A3 
30 47 Friday, December 08, 2017 
Bryce Canyon_IO Module 
http://www.wiwynn.com 
8F, 90, Sec.1, Xintai 5th Rd., Xizhi Dist.,
New Taipei City 22102, Taiwan (R.O.C.)
R509 
4K75R2F-1-GP 
NOPOP 4.75k ohm 
1/16W 
1% 
0402 
1 2
C198 
SCD1U16V2KX-3GP 
0.1uF 
16V 
10% 
0402 
X7R 
1 2
R507 
10KR2F-2-GP 
10k ohm 
1/16W 
1% 
0402 
1 2
R510 0 ohm 0402 12
R505 
3K57R2F-GP 
3.57k ohm 
1/16W 
1% 
0402 
1 2
C194 
SC10U6D3V5KX-4GP 
10uF 
6.3V 
10% 
0805 
X7R 
1 2
C192 
SC10U6D3V5KX-4GP 
10uF 
6.3V 
10% 
0805 
X7R 
1 2
C190 
SC1KP50V2KX-1GP 
NOPOP 1000pF 
50V 
10% 
0402 
X7R 
1 2
C200 
SC10U6D3V5KX-4GP 
10uF 
6.3V 
10% 
0805 
X7R 
1 2
R508 
0R2J-2-GP 
0 ohm 
1/16W 
5% 
0402 
1 2
C201 
SCD1U16V2KX-3GP 
NOPOP 
0.1uF 
16V 
10% 
0402 
X7R 
1 2
C197 
SC1U16V3KX-5GP 
1uF 
16V 
10% 
0603 
X7R 
1 2
C199 
SC10U6D3V5KX-4GP 
10uF 
6.3V 
10% 
0805 
X7R 
1 2
C195 
SCD1U16V2KX-3GP
0.1uF 
16V 
10% 
0402 
X7R
1 2
PU9 
TPS74801RGW-GP OUT#1 1
NC#2 2 NC#3 3 NC#4 4
IN#5 5IN#6 6IN#7 7IN#8 8
PG 9
BIAS 10 
EN 11 
GND 12 
NC#13 13 NC#14 14 
SS 15 
FB 16 
NC#17 17 
OUT#18 18 
OUT#19 19 
OUT#20 20 
GND 21 
C193 
SC10U6D3V5KX-4GP 
10uF 
6.3V 
10% 
0805 
X7R 
1 2
R506 
1K69R2F-2-GP 
1.69k ohm 
1/16W 
1% 
0402 
1 2
C196 
SC470P50V2KX-3GP 
470pF 
50V 
10% 
0402 
X7R 
12
C191 
SC10U6D3V5KX-4GP 
10uF 
6.3V 
10% 
0805 
X7R 
1 2
R504 
0R5J-5-GP 
0 ohm 
1/8W 
5% 
0805 
1 2



5
5
4
4
3
3
2
2
1
1
D D
C C
B B
A A
Power rail : P1V8_STBY 
Controller : TPS53312(Fswitching=700KHz) 
TDC : 2.178A 
MAX : 2.178A 
OCP : 4.1A 
P1V8_STBY_SNB 
P1V8_STBY_SW 
P1V8_STBY_CC_R P1V8_STBY_CC 
P1V8_STBY_VBST_RR 
P12V_STBY_VCC_PU4 
P1V8_STBY_EN_R 
P1V8_STBY_VO 
P1V8_STBY_VFB 
P1V8_STBY_SS 
P1V8_STBY_VRG5 
P1V8_STBY_VBST 
P1V8_STBY_VFB 
P1V8_STBY_CC 
P1V8_STBY_VFB_R 
P1V8_STBY_SW 
P12V_STBY_VIN_PU4 
PQ4_G 
PQ4_D 
P3V3_PG 
Q7_G 
Q6_G 
P1V8_EN P3V3_PG 
AGND_P1V8_STBY 
AGND_P1V8_STBY 
P1V8_STBY 
AGND_P1V8_STBY 
P12V_STBY P12V_STBY 
AGND_P1V8_STBY 
P1V8_STBY 
P1V8 
P3V3_STBY 
P12V_STBY 
P1V8_STBY 
P3V3 
P3V3_STBY 
P3V3 
PWRGD_P1V8_STBY 32 
PWRGD_P2V5_STBY 30 
Title 
Size Document Number Rev
Date: Sheet 
of 
Bryce Canyon_IO Module 2A3 
31 47 Friday, December 08, 2017 
Bryce Canyon_IO Module 
http://www.wiwynn.com 
8F, 90, Sec.1, Xintai 5th Rd., Xizhi Dist.,
New Taipei, Taiwan 
PWRSW_P1V8_STBY_TPS53312 
Title 
Size Document Number Rev
Date: Sheet 
of 
Bryce Canyon_IO Module 2A3 
31 47 Friday, December 08, 2017 
Bryce Canyon_IO Module 
http://www.wiwynn.com 
8F, 90, Sec.1, Xintai 5th Rd., Xizhi Dist.,
New Taipei, Taiwan 
PWRSW_P1V8_STBY_TPS53312 
Title 
Size Document Number Rev
Date: Sheet 
of 
Bryce Canyon_IO Module 2A3 
31 47 Friday, December 08, 2017 
Bryce Canyon_IO Module 
http://www.wiwynn.com 
8F, 90, Sec.1, Xintai 5th Rd., Xizhi Dist.,
New Taipei, Taiwan 
PWRSW_P1V8_STBY_TPS53312 
R521 
15KR2F-GP 
15k ohm 
1/16W 
1% 
0402 
1 2
L10 
COIL-3D3UH-48-GP 
1 2
C218 
SC10U6D3V5KX-4GP 
10uF 
6.3V 
10% 
0805 
X7R 
1 2
R528 
1KR2F-3-GP 
1k ohm 
1/16W 
1% 
0402 
1 2
PU4 
TPS53312RGTR-GP 
VBST 12 
VIN#13 13 
SW#9 9
VREG5 2
PG 5
GND 4
SS 3
VFB 1
VO 16 
VCC 15 
EN 6 SW#10 10 
SW#11 11 
VIN#14 14 
PGND 7
PGND 8GND 17 
C208 
SC3300P50V2KX-1GP 
3300pF 
50V 
10% 
0402 
X7R 
1 2
C209 
SC1U16V3KX-5GP 
1uF 
16V 
10% 
0603 
X7R 
1 2
C216 
SC10U6D3V5KX-4GP 
10uF 
6.3V 
10% 
0805 
X7R 
1 2
R517 
0R2J-2-GP 
0 ohm 1/16W 5% 0402 
12
R527 
4K7R2F-GP 
4.7k ohm 
1/16W 
1% 
0402 
1 2
C205 
SC10U16V5KX-7-GP-U 
10uF 
16V 
10% 
0805 
X7R 
1 2
R515 13K7R2F-GP 1 2
Q7 
2N7002K-1-GP 
G
D S
R522 0R2J-2-GP 
0 ohm 1/16W 5% 0402 
12
R518 
10KR2F-2-GP 
10k ohm 
1/16W 
1% 
0402 
1 2 C211 
SCD1U50V3KX-GP 
0.1uF 
50V 
10% 
0603 
X7R 
NOPOP 
1 2
C202 SC1U16V3KX-5GP 
1uF 16V 10% 0603 X7R 
1 2
D5 
SMF15A-GP 
NOPOP 
AK
C220 
SC10U6D3V5KX-4GP 
10uF 
6.3V 
10% 
0805 
X7R 
1 2
C203 
SCD1U16V2KX-3GP 
0.1uF 
16V 
10% 
0402 
X7R 
1 2
R524 
4K7R2F-GP 
4.7k ohm 
1/16W 
1% 
0402 
1 2
C212 
SC1KP50V2KX-1GP 
NOPOP 
1000pF 
50V 
10% 
0402 
X7R 
1 2
C210 
SC2200P50V2KX-2GP 
2200pF 
50V 
10% 
0402 
X7R 
NOPOP 
1 2
PQ4 
2N7002K-1-GP 
G
DS
C213 
SC1U16V3KX-5GP 
1uF 
16V 
10% 
0603 
X7R 
NOPOP 
12
C510 
SCD1U16V2KX-3GP 
0.1uF 
16V 
10% 
0402 
X7R 
NOPOP 
1 2
C217 
SC10U6D3V5KX-4GP 
10uF 
6.3V 
10% 
0805 
X7R 
1 2
R519 
1KR2F-3-GP 
NOPOP 1k ohm 
1/16W 
1% 
0402 
1 2
R523 
4K53R2F-1-GP 
4.53k ohm 
1/16W 
1% 
0402 
12
R511 2D2R3-1-U-GP 
2.2 ohm 1/10W 1% 0603 
12
G5 
COPPER-CLOSE-GP-U 
1 2
C207 
SCD1U50V3KX-GP 
0.1uF 
50V 
10% 
0603 
X7R 
1 2
C215 
SC10U6D3V5KX-4GP 
10uF 
6.3V 
10% 
0805 
X7R 
1 2
R512 0R6J-3-GP 
0 ohm 1/4W 5% 1206 
1 2
R516 0R2J-2-GP 
0 ohm 1/16W 5% 0402 
12
C204 
SC10U16V5KX-7-GP-U 
10uF 
16V 
10% 
0805 
X7R 
1 2
R526 
4K7R2F-GP 
4.7k ohm 
1/16W 
1% 
0402 
1 2
C206 SC100P50V2JN-3GP 
100pF 50V 5% 0402 NPO 
1 2
R525 
10KR2F-2-GP 
10k ohm 
1/16W 
1% 
0402 
1 2
G4 
GAP-CLOSE-PWR-4-GP
1 2
R520 
3D01R5F-GP 
NOPOP 
3.01 ohm 
1/8W 
1% 
0805 
1 2
C221 
SCD1U25V2KX-2-GP 
0.1uF 
25V 
10% 
0402 
X7R 
1 2
C214 
SCD1U16V2KX-3GP 
0.1uF 
16V 
10% 
0402 
X7R 
1 2
C219 
SCD47U25V3KX-3-GP 
0.47uF 
25V 
10% 
0603 
X7R 
1 2
R513 10KR2F-2-GP 
10k ohm 1/16W 1% 0402 
1 2
R514 10R3F-GP 
10 ohm 1/10W 1% 0603 
1 2
R727 0R2J-2-GP 
0 ohm 1/16W 5% 0402 
12
Q6 
2N7002K-1-GP 
G
D S
S
S
S
G D
D
D
D
PQ5 
FDS8878-G-GP 
1
2
3
45
6
7
8



5
5
4
4
3
3
2
2
1
1
D D
C C
B B
A A
Power rail :P1V2_STBY(1.2V) 
Controller :TPS74801 
TDC :0.495A 
Max :0.495A 
OCP:2A 
TPS74801_P1V2_STBY_OUT 
TPS74801_P1V2_STBY_EN 
TPS74801_P1V2_STBY_SS 
TPS74801_P1V2_STBY_BIAS 
TPS74801_P1V2_STBY_FB 
P1V8_STBY 
P1V2_STBY 
P3V3_STBY 
P5V_STBY 
P3V3_STBY 
PWRGD_P1V8_STBY 31 
PWRGD_P1V2_STBY 33 
Title 
Size Document Number Rev
Date: Sheet 
of 
Bryce Canyon_IO Module 2
PWRLDO_P1V2_STBY_TPS74801 
A3 
32 47 Friday, December 08, 2017 
Bryce Canyon_IO Module 
http://www.wiwynn.com 
8F, 90, Sec.1, Xintai 5th Rd., Xizhi Dist.,
New Taipei City 22102, Taiwan (R.O.C.)
Title 
Size Document Number Rev
Date: Sheet 
of 
Bryce Canyon_IO Module 2
PWRLDO_P1V2_STBY_TPS74801 
A3 
32 47 Friday, December 08, 2017 
Bryce Canyon_IO Module 
http://www.wiwynn.com 
8F, 90, Sec.1, Xintai 5th Rd., Xizhi Dist.,
New Taipei City 22102, Taiwan (R.O.C.)
Title 
Size Document Number Rev
Date: Sheet 
of 
Bryce Canyon_IO Module 2
PWRLDO_P1V2_STBY_TPS74801 
A3 
32 47 Friday, December 08, 2017 
Bryce Canyon_IO Module 
http://www.wiwynn.com 
8F, 90, Sec.1, Xintai 5th Rd., Xizhi Dist.,
New Taipei City 22102, Taiwan (R.O.C.)
R530 
2K49R2F-GP 
2.49k ohm 
1/16W 
1% 
0402 
1 2
C230 
SCD1U16V2KX-3GP 
0.1uF 
16V 
10% 
0402 
X7R 
1 2
C226 
SC10U6D3V5KX-4GP 
10uF 
6.3V 
10% 
0805 
X7R 
1 2
C225 
SC10U6D3V5KX-4GP 
10uF 
6.3V 
10% 
0805 
X7R 
1 2
PU10 
TPS74801RGW-GP OUT#1 1
NC#2 2 NC#3 3 NC#4 4
IN#5 5IN#6 6IN#7 7IN#8 8
PG 9
BIAS 10 
EN 11 
GND 12 
NC#13 13 NC#14 14 
SS 15 
FB 16 
NC#17 17 
OUT#18 18 
OUT#19 19 
OUT#20 20 
GND 21 
C224 
SC10U6D3V5KX-4GP 
10uF 
6.3V 
10% 
0805 
X7R 
1 2
R529 
0R5J-5-GP 
0 ohm 
1/8W 
5% 
0805 
1 2
R531 
4K99R2F-L-GP 
4.99k ohm 
1/16W 
1% 
0402 
1 2
R534 
4K75R2F-1-GP 
NOPOP 4.75k ohm 
1/16W 
1% 
0402 
1 2
R533 
0R2J-2-GP 
0 ohm 
1/16W 
5% 
0402 
1 2
C231 
SC10U6D3V5KX-4GP 
10uF 
6.3V 
10% 
0805 
X7R 
1 2
R532 
10KR2F-2-GP 
10k ohm 
1/16W 
1% 
0402 
1 2
C222 
SC1KP50V2KX-1GP 
NOPOP 1000pF 
50V 
10% 
0402 
X7R 
1 2
C233 
SCD1U16V2KX-3GP 
NOPOP 
0.1uF 
16V 
10% 
0402 
X7R 
1 2
C228 
SC470P50V2KX-3GP 
470pF 
50V 
10% 
0402 
X7R 
12
C223 
SC10U6D3V5KX-4GP 
10uF 
6.3V 
10% 
0805 
X7R 
1 2
C232 
SC10U6D3V5KX-4GP 
10uF 
6.3V 
10% 
0805 
X7R 
1 2
R535 0R2J-2-GP 
0 ohm 1/16W 5% 0402 
12
C227 
SCD1U16V2KX-3GP
0.1uF 
16V 
10% 
0402
X7R
1 2
C229 
SC1U16V3KX-5GP 
1uF 
16V 
10% 
0603 
X7R 
1 2



5
5
4
4
3
3
2
2
1
1
D D
C C
B B
A A
Power rail :P1V15_STBY(1.15V) 
Controller :TPS74801 
TDC :0.663A 
Max :0.663A 
OCP:2A 
TPS74801_P1V15_STBY_OUT 
TPS74801_P1V15_STBY_FB 
TPS74801_P1V15_STBY_EN 
TPS74801_P1V15_STBY_SS 
TPS74801_P1V15_STBY_BIAS 
P1V15_STBY_PG 
P1V15_STBY_PG_G 
P1V15_STBY_PG 
P1V8_STBY 
P1V15_STBY 
P3V3_STBY 
P5V_STBY 
P3V3_STBY 
P3V3_STBY 
P5V_STBY 
PWRGD_P1V2_STBY 32 
IOM_STBY_PGOOD 22,29 
Title 
Size Document Number Rev
Date: Sheet 
of 
Bryce Canyon_IO Module 2
PWRLDO_P1V15_STBY_TPS74801 
A3 
33 47 Friday, December 08, 2017 
Bryce Canyon_IO Module 
http://www.wiwynn.com 
8F, 90, Sec.1, Xintai 5th Rd., Xizhi Dist.,
New Taipei City 22102, Taiwan (R.O.C.)
Title 
Size Document Number Rev
Date: Sheet 
of 
Bryce Canyon_IO Module 2
PWRLDO_P1V15_STBY_TPS74801 
A3 
33 47 Friday, December 08, 2017 
Bryce Canyon_IO Module 
http://www.wiwynn.com 
8F, 90, Sec.1, Xintai 5th Rd., Xizhi Dist.,
New Taipei City 22102, Taiwan (R.O.C.)
Title 
Size Document Number Rev
Date: Sheet 
of 
Bryce Canyon_IO Module 2
PWRLDO_P1V15_STBY_TPS74801 
A3 
33 47 Friday, December 08, 2017 
Bryce Canyon_IO Module 
http://www.wiwynn.com 
8F, 90, Sec.1, Xintai 5th Rd., Xizhi Dist.,
New Taipei City 22102, Taiwan (R.O.C.)
R723 
4K7R2F-GP 
4.7k ohm 
1/16W 
1% 
0402 
1 2
C241 
SC1U16V3KX-5GP 
1uF 
16V 
10% 
0603 
X7R 
1 2
C245 
SCD1U16V2KX-3GP 
NOPOP 
0.1uF 
16V 
10% 
0402 
X7R 
1 2
C236 
SC10U6D3V5KX-4GP 
10uF 
6.3V 
10% 
0805 
X7R 
1 2
C240 
SC470P50V2KX-3GP 
470pF 
50V 
10% 
0402 
X7R 
12
R726 
4K7R2F-GP 
4.7k ohm 
1/16W 
1% 
0402 
1 2
R539 
10KR2F-2-GP 
10k ohm 
1/16W 
1% 
0402 
1 2
Q11 
2N7002K-1-GP 
G
D S
C239 
SCD1U16V2KX-3GP 
0.1uF 
16V 
10% 
0402 
X7R 
1 2
C243 
SC10U6D3V5KX-4GP 
10uF 
6.3V 
10% 
0805 
X7R 
1 2
C234 
SC1KP50V2KX-1GP 
NOPOP 1000pF 
50V 
10% 
0402 
X7R 
1 2
Q12 
2N7002K-1-GP 
G
D S
C237 
SC10U6D3V5KX-4GP 
10uF 
6.3V 
10% 
0805 
X7R 
1 2
R538 
4K64R2F-GP 
4.64k ohm 
1/16W 
1% 
0402 
1 2
C244 
SC10U6D3V5KX-4GP 
10uF 
6.3V 
10% 
0805 
X7R 
1 2
C242 
SCD1U16V2KX-3GP 
0.1uF 
16V 
10% 
0402 
X7R 
1 2
R541 
4K75R2F-1-GP 
NOPOP 
4.75k ohm 
1/16W 
1% 
0402 
1 2
C235 
SC10U6D3V5KX-4GP 
10uF 
6.3V 
10% 
0805 
X7R 
1 2
C524 
SC1U16V2KX-7-GP 
1uF 
16V 
10% 
0402 
X6S 
1 2
PU11 
TPS74801RGW-GP OUT#1 1
NC#2 2 NC#3 3 NC#4 4
IN#5 5IN#6 6IN#7 7IN#8 8
PG 9
BIAS 10 
EN 11 
GND 12 
NC#13 13 NC#14 14 
SS 15 
FB 16 
NC#17 17 
OUT#18 18 
OUT#19 19 
OUT#20 20 
GND 21 
R540 
0R2J-2-GP 
0 ohm 
1/16W 
5% 
0402 
1 2
R537 
2K05R2F-1-GP 
2.05k ohm 
1/16W 
1% 
0402 
1 2
R542 0R2J-2-GP 
0 ohm 1/16W 5% 0402 
1 2
C238 
SC10U6D3V5KX-4GP 
10uF 
6.3V 
10% 
0805 
X7R 
1 2
R536 
0R5J-5-GP 
0 ohm 
1/8W 
5% 
0805 
1 2



5
5
4
4
3
3
2
2
1
1
D D
C C
B B
A A
Power rail :P1V5(1.5V) 
Controller :TPS74801 
TDC :0.36A 
Max :0.36A 
OCP:2A 
PWRGD_P1V8 
TPS74801_1V5_EN 
TPS74801_1V5_SS 
TPS74801_1V5_BIAS 
TPS74801_P1V5_FB 
P1V5_OUT 
PWRGD_P1V8 
Q9_G 
Q8_G 
P3V3_STBY 
P1V8_STBY 
P5V_STBY 
P1V5 
P3V3_STBY 
P1V8 
P3V3_STBY 
P1V8 
PWRGD_P1V5 35 
PWRGD_P1V8 39 
Title 
Size Document Number Rev
Date: Sheet 
of 
Bryce Canyon_IO Module 2
PWRLDO_P1V5_STBY_TPS74801 
A3 
34 47 Friday, December 08, 2017 
Bryce Canyon_IO Module 
http://www.wiwynn.com 
8F, 90, Sec.1, Xintai 5th Rd., Xizhi Dist.,
New Taipei City 22102, Taiwan (R.O.C.)
Title 
Size Document Number Rev
Date: Sheet 
of 
Bryce Canyon_IO Module 2
PWRLDO_P1V5_STBY_TPS74801 
A3 
34 47 Friday, December 08, 2017 
Bryce Canyon_IO Module 
http://www.wiwynn.com 
8F, 90, Sec.1, Xintai 5th Rd., Xizhi Dist.,
New Taipei City 22102, Taiwan (R.O.C.)
Title 
Size Document Number Rev
Date: Sheet 
of 
Bryce Canyon_IO Module 2
PWRLDO_P1V5_STBY_TPS74801 
A3 
34 47 Friday, December 08, 2017 
Bryce Canyon_IO Module 
http://www.wiwynn.com 
8F, 90, Sec.1, Xintai 5th Rd., Xizhi Dist.,
New Taipei City 22102, Taiwan (R.O.C.)
C256 
SC10U6D3V5KX-4GP 
10uF 
6.3V 
10% 
0805 
X7R 
1 2
C246 
SC1KP50V2KX-1GP 
NOPOP 1000pF 
50V 
10% 
0402 
X7R 
1 2
C253 
SC1U16V3KX-5GP 
1uF 
16V 
10% 
0603 
X7R 
1 2
C252 
SC470P50V2KX-3GP 
470pF 
50V 
10% 
0402 
X7R 
12
R549 0R2J-2-GP 
0 ohm 1/16W 5% 0402 
1 2
R551 
4K7R2F-GP 
4.7k ohm 
1/16W 
1% 
0402 
1 2
R547 
0R2J-2-GP 
0 ohm 
1/16W 
5% 
0402 
1 2
C250 
SC10U6D3V5KX-4GP 
10uF 
6.3V 
10% 
0805 
X7R 
1 2
C248 
SC10U6D3V5KX-4GP 
10uF 
6.3V 
10% 
0805 
X7R 
1 2
C251 
SCD1U16V2KX-3GP 
0.1uF 
16V 
10% 
0402 
X7R 
1 2
R543 
0R5J-5-GP 
0 ohm 
1/8W 
5% 
0805 
1 2
Q9 
SSM3K324R-GP 
S
G
D
C257 
SCD1U16V2KX-3GP 
NOPOP 
0.1uF 
16V 
10% 
0402 
X7R 
1 2
R545 
4K75R2F-1-GP 
4.75k ohm 
1/16W 
1% 
0402 
1 2
R548 
4K75R2F-1-GP 
NOPOP 4.75k ohm 
1/16W 
1% 
0402 
1 2
C255 
SC10U6D3V5KX-4GP 
10uF 
6.3V 
10% 
0805 
X7R 
1 2
R552 
4K7R2F-GP 
4.7k ohm 
1/16W 
1% 
0402 
1 2
R544 
4K22R2F-GP 
4.22k ohm 
1/16W 
1% 
0402 
1 2
Q8 
2N7002K-1-GP 
G
D S
R550 
4K7R2F-GP 
4.7k ohm 
1/16W 
1% 
0402 
1 2
C249 
SC10U6D3V5KX-4GP 
10uF 
6.3V 
10% 
0805 
X7R 
1 2
C247 
SC10U6D3V5KX-4GP 
10uF 
6.3V 
10% 
0805 
X7R 
1 2
R546 
10KR2F-2-GP 
10k ohm 
1/16W 
1% 
0402 
1 2
C254 
SCD1U16V2KX-3GP 
0.1uF 
16V 
10% 
0402 
X7R 
1 2
PU7 
TPS74801RGW-GP OUT#1 1
NC#2 2 NC#3 3 NC#4 4
IN#5 5IN#6 6IN#7 7IN#8 8
PG 9
BIAS 10 
EN 11 
GND 12 
NC#13 13 NC#14 14 
SS 15 
FB 16 
NC#17 17 
OUT#18 18 
OUT#19 19 
OUT#20 20 
GND 21 



5
5
4
4
3
3
2
2
1
1
D D
C C
B B
A A
Power rail :P0V975(0.975V) 
Controller :VT235WFQX 
Fswitch= 300KHz 
TDC : 14.37A 
Max : 14.37A 
OCP :20A 
VT235_EN 
VT235_IRIP 
VT235_VDES_RC 
VT235_VDDH 
VT235_PGIN 
VT235_BIAS 
VT235_VDES 
VT235_BST 
VT235_VFB 
VT235_VDES_RCC 
VT235_IMAX 
IOM_FULL_PGOOD 
VT235_VREF 
VT235_VREF 
VT235_AVDD 
VT235_VDDL 
VT235_VDES_RR 
VT235_PGIN 
IOM_FULL_PGOOD 
P0V975_SEN 
GND_SEN 
VT235_VX 
P3V3_STBY 
AGND_P0V975 
P12V_STBY 
AGND_P0V975 
P0V975 
P0V975 
AGND_P0V975 
AGND_P0V975 
AGND_P0V975 
P3V3_STBY P3V3_STBY 
P1V8 
AVSO_VREF 39 
PWRGD_P1V5 34 
IOM_FULL_PGOOD 21,44 
PWRGD_P0V975 39 
Title 
Size Document Number Rev
Date: Sheet 
of 
Bryce Canyon_IO Module 2
PWRSW_P0V975_STBY_VT235WFQX 
A2 
35 47 Friday, December 08, 2017 
Bryce Canyon_IO Module 
http://www.wiwynn.com 
8F, 90, Sec.1, Xintai 5th Rd., Xizhi Dist.,
New Taipei City 22102, Taiwan (R.O.C.)
Title 
Size Document Number Rev
Date: Sheet 
of 
Bryce Canyon_IO Module 2
PWRSW_P0V975_STBY_VT235WFQX 
A2 
35 47 Friday, December 08, 2017 
Bryce Canyon_IO Module 
http://www.wiwynn.com 
8F, 90, Sec.1, Xintai 5th Rd., Xizhi Dist.,
New Taipei City 22102, Taiwan (R.O.C.)
Title 
Size Document Number Rev
Date: Sheet 
of 
Bryce Canyon_IO Module 2
PWRSW_P0V975_STBY_VT235WFQX 
A2 
35 47 Friday, December 08, 2017 
Bryce Canyon_IO Module 
http://www.wiwynn.com 
8F, 90, Sec.1, Xintai 5th Rd., Xizhi Dist.,
New Taipei City 22102, Taiwan (R.O.C.)
R568 
10KR2F-2-GP 
10k ohm 
1/16W 
1% 
0402 
1 2
C285 
SCD1U50V3KX-GP 
0.1uF 
50V 
10% 
0603 
X7R 
1 2
C283 
SC22U6D3V6KX-2-GP 
22uF 
6.3V 
10% 
1206 
X7R 
1 2
C261 
SC22U6D3V6KX-2-GP 
22uF 
6.3V 
10% 
1206 
X7R 
1 2
C269 
SC10U16V5KX-7-GP-U 
10uF 
16V 
10% 
0805 
X7R 
1 2
R562 
100KR2F-L1-GP 
100k ohm 
1/16W 
1% 
0402 
1 2
C265 
SC22U6D3V6KX-2-GP 
22uF 
6.3V 
10% 
1206 
X7R 
1 2
C287 
SC1KP50V2KX-1GP 
1000pF 
50V 
10% 
0402 
X7R 
1 2
R7909 
2D2R5F-2-GP 
NONPOP 
1 2
R349 
0 ohm 
0402 
1 2
R556 
10KR2F-2-GP NOPOP 
10k ohm 
1/16W 
1% 
0402 
1 2
R564 
7K32R2F-GP 
7.32k ohm 
1/16W 
1% 
0402 
1 2
C273 
SC10U16V5KX-7-GP-U 
10uF 
16V 
10% 
0805 
X7R 
1 2
L12 
COIL-D24UH-GP 
1 2
C277 
SC1U25V3KX-GP 
1uF 
25V 
10% 
0603 
X7R 
1 2 R557 
1K21R2F-2-GP 
1.21k ohm 
1/16W 
1% 
0402 
1 2
C267 SC1U25V3KX-GP 
1uF 25V 10% 0603 X7R 
1 2
R561 10KR2F-2-GP 
10k ohm 1/16W 1% 0402 
1 2
C282 
SC1U25V3KX-GP 
1uF 
25V 
10% 
0603 
X7R 
1 2
C509 
SE470UF2VDM-GP 
470uF 
2V 
Irp=3.5A 
ESR= 6mOhm 
Tmax=105C 
1 2
C279 
SC6K8P50V2KX-GP 
6800pF 
50V 
10% 
0402 
X7R 
1 2
PSP1 
COPPER-CLOSE-GP-U 
1 2
C278 
SC1U25V3KX-GP 
1uF 
25V 
10% 
0603 
X7R 
1 2
C272 
SC10U16V5KX-7-GP-U 
10uF 
16V 
10% 
0805 
X7R 
1 2
R615 
0 ohm 
0402 
1 2
R559 10KR2F-2-GP 
10k ohm 1/16W 1% 0402 
1 2
C264 
SC22U6D3V6KX-2-GP 
22uF 
6.3V 
10% 
1206 
X7R 
1 2
C281 
SC220P50V2KX-3GP 
220pF 
50V 
10% 
0402 
X7R 
1 2
C263 
SCD1U50V3KX-GP 
0.1uF 
50V 
10% 
0603 
X7R 
1 2
R558 0R2J-2-GP 
0 ohm 1/16W 5% 0402 
1 2
C259 
SC22U6D3V6KX-2-GP 
22uF 
6.3V 
10% 
1206 
X7R 
1 2
C288 
SCD1U50V3KX-GP 
0.1uF 
50V 
10% 
0603 
X7R 
1 2
C258 
SC22U6D3V6KX-2-GP 
22uF 
6.3V 
10% 
1206 
X7R 
1 2
R560 69K8R2F-GP 
69.8k ohm 1/16W 1% 0402 
1 2
C262 
SC6K8P50V2KX-GP 
6800pF 
50V 
10% 
0402 
X7R 
1 2
R553 
10KR2F-2-GP 
10k ohm 
1/16W 
1% 
0402 
1 2
R565 221R2F-2-GP 
221 ohm 1/16W 1% 0402 
1 2
C271 
SC10U16V5KX-7-GP-U 
10uF 
16V 
10% 
0805 
X7R 
1 2
C274 
SC10U16V5KX-7-GP-U 
10uF 
16V 
10% 
0805 
X7R 
1 2
C266 
SC22U6D3V6KX-2-GP
22uF 
6.3V 
10% 
1206 
X7R 
1 2
C286 
SCD33U16V3KX-1GP 
0.33uF 
16V 
10% 
0603 
X7R 
1 2
C276 
SC4700P25V2KX-3-GP 
1 2
C324 
SE470UF2VDM-GP 
470uF 
2V 
Irp=3.5A 
ESR= 6mOhm 
Tmax=105C 
1 2
R566 
453R2F-1-GP 
453 ohm 
1/16W 
1% 
0402 
1 2
L11 
BLM41PG600-GP 
60Ohm@100MHz 
Imax=6A 
DCR=20mOhm 
Tmax=125C 
1 2
C280 
SC1U10V2KX-1GP 
NOPOP 
1uF 
10V 
10% 
0402 
X5R 
12
C275 
SC10U16V5KX-7-GP-U 
10uF 
16V 
10% 
0805 
X7R 
1 2
U95 
SN74LVC1G07DCKR-GP 
GND 3 A2 NC#1 1 VCC 5
Y 4
PU8 
VT235WFQX-ADJ-1-GP 
STAT 17 
EN 18 
IMAX 16 
IRPL 19 
VBIAS 15 
VDDL 9
RES1 10 
AVDD 3
VDDH 4
BST 8
VX#6 6
VX#7 7
PGIN 12 
VFB 11 
VDES 13 
VREF 14 
NODR 2
AGND 1 GND 5
R554 
19K1R2F-GP 
19.1k ohm 
1/16W 
1% 
0402 
1 2
C270 
SC10U16V5KX-7-GP-U 
10uF 
16V 
10% 
0805 
X7R 
1 2
C260 
SC22U6D3V6KX-2-GP 
22uF 
6.3V 
10% 
1206 
X7R 
1 2
C268 
SC22U6D3V6KX-2-GP 
22uF 
6.3V 
10% 
1206 
X7R 
1 2
C744 
SC2200P50V2KX-2GP NOPOP 
2200pF 
50V 
10% 
0402 
X7R 
1 2
R555 221R2F-2-GP 
221 ohm 1/16W 1% 0402 
1 2
R563 
100KR2F-L1-GP 
NOPOP 100k ohm 
1/16W 
1% 
0402 
1 2
R567 
4K7R2F-GP 
4.7k ohm 
1/16W 
1% 
0402 
12
C284 
SCD01U25V2KX-3GP 
0.01uF 
25V 
10% 
0402 
X7R 
1 2



5
5
4
4
3
3
2
2
1
1
D D
C C
B B
A A
PCIE_IOM_TO_COMP_8_DP_C 
PCIE_IOM_TO_COMP_8_DN_C 
PCIE_COMP_TO_IOM_CLK_2_DN 
PCIE_COMP_TO_IOM_CLK_2_DP 
PCIE_COMP_TO_IOM_CLK_2_DP 
PCIE_COMP_TO_IOM_CLK_2_DN 
PCIE_IOM_TO_COMP_9_DP_C 
PCIE_IOM_TO_COMP_9_DN_C 
PCIE_IOM_TO_COMP_10_DP_C 
PCIE_IOM_TO_COMP_10_DN_C 
PCIE_IOM_TO_COMP_11_DP_C 
PCIE_IOM_TO_COMP_11_DN_C 
PCIE_IOM_TO_COMP_12_DP_C 
PCIE_IOM_TO_COMP_12_DN_C 
PCIE_IOM_TO_COMP_13_DP_C 
PCIE_IOM_TO_COMP_13_DN_C 
PCIE_IOM_TO_COMP_14_DP_C 
PCIE_IOM_TO_COMP_14_DN_C 
PCIE_IOM_TO_COMP_15_DN_C 
PCIE_IOM_TO_COMP_15_DP_C 
PCIE_COMP_TO_IOM_8_DP 
PCIE_COMP_TO_IOM_8_DN 
PCIE_COMP_TO_IOM_9_DN 
PCIE_COMP_TO_IOM_9_DP 
PCIE_COMP_TO_IOM_10_DN 
PCIE_COMP_TO_IOM_10_DP 
PCIE_COMP_TO_IOM_11_DN 
PCIE_COMP_TO_IOM_11_DP 
PCIE_COMP_TO_IOM_12_DN 
PCIE_COMP_TO_IOM_12_DP 
PCIE_COMP_TO_IOM_13_DN 
PCIE_COMP_TO_IOM_13_DP 
PCIE_COMP_TO_IOM_14_DN 
PCIE_COMP_TO_IOM_14_DP 
PCIE_COMP_TO_IOM_15_DN 
PCIE_COMP_TO_IOM_15_DP 
PCIE_COMP_TO_IOM_8_DP 
PCIE_COMP_TO_IOM_8_DN 
PCIE_COMP_TO_IOM_9_DP 
PCIE_COMP_TO_IOM_9_DN 
PCIE_COMP_TO_IOM_10_DN 
PCIE_COMP_TO_IOM_10_DP 
PCIE_COMP_TO_IOM_11_DP 
PCIE_COMP_TO_IOM_11_DN 
PCIE_COMP_TO_IOM_12_DP 
PCIE_COMP_TO_IOM_12_DN 
PCIE_COMP_TO_IOM_13_DN 
PCIE_COMP_TO_IOM_13_DP 
PCIE_COMP_TO_IOM_14_DN 
PCIE_COMP_TO_IOM_14_DP 
PCIE_COMP_TO_IOM_15_DN 
PCIE_COMP_TO_IOM_15_DP 
PCIE_COMP_TO_IOM_CLK_2_DN 
PCIE_COMP_TO_IOM_CLK_2_DP 
PCIE_COMP_TO_IOM_CLK_2_DN 11 
PCIE_COMP_TO_IOM_CLK_2_DP 11 
PCIE_IOM_TO_COMP_8_DN 11 
PCIE_IOM_TO_COMP_8_DP 11 
PCIE_IOM_TO_COMP_9_DP 11 
PCIE_IOM_TO_COMP_9_DN 11 
PCIE_IOM_TO_COMP_10_DN 11 
PCIE_IOM_TO_COMP_10_DP 11 
PCIE_IOM_TO_COMP_11_DN 11 
PCIE_IOM_TO_COMP_11_DP 11 
PCIE_IOM_TO_COMP_12_DP 11 
PCIE_IOM_TO_COMP_12_DN 11 
PCIE_IOM_TO_COMP_13_DN 11 
PCIE_IOM_TO_COMP_13_DP 11 
PCIE_IOM_TO_COMP_14_DN 11 
PCIE_IOM_TO_COMP_14_DP 11 
PCIE_IOM_TO_COMP_15_DN 11 
PCIE_IOM_TO_COMP_15_DP 11 
PCIE_COMP_TO_IOM_8_DP 11 
PCIE_COMP_TO_IOM_8_DN 11 
PCIE_COMP_TO_IOM_9_DN 11 
PCIE_COMP_TO_IOM_9_DP 11 
PCIE_COMP_TO_IOM_10_DN 11 
PCIE_COMP_TO_IOM_10_DP 11 
PCIE_COMP_TO_IOM_11_DN 11 
PCIE_COMP_TO_IOM_11_DP 11 
PCIE_COMP_TO_IOM_12_DP 11 
PCIE_COMP_TO_IOM_12_DN 11 
PCIE_COMP_TO_IOM_13_DN 11 
PCIE_COMP_TO_IOM_13_DP 11 
PCIE_COMP_TO_IOM_14_DN 11 
PCIE_COMP_TO_IOM_14_DP 11 
PCIE_COMP_TO_IOM_15_DN 11 
PCIE_COMP_TO_IOM_15_DP 11 
Title 
Size Document Number Rev
Date: Sheet 
of 
Bryce Canyon_IO Module 2
SAS3008_PCIE & SAS 
A3 
36 47Friday, December 08, 2017 
Bryce Canyon_IO Module 
http://www.wiwynn.com 
8F, 90, Sec.1, Xintai 5th Rd., Xizhi Dist.,
New Taipei City 22102, Taiwan (R.O.C.)
Title 
Size Document Number Rev
Date: Sheet 
of 
Bryce Canyon_IO Module 2
SAS3008_PCIE & SAS 
A3 
36 47Friday, December 08, 2017 
Bryce Canyon_IO Module 
http://www.wiwynn.com 
8F, 90, Sec.1, Xintai 5th Rd., Xizhi Dist.,
New Taipei City 22102, Taiwan (R.O.C.)
Title 
Size Document Number Rev
Date: Sheet 
of 
Bryce Canyon_IO Module 2
SAS3008_PCIE & SAS 
A3 
36 47Friday, December 08, 2017 
Bryce Canyon_IO Module 
http://www.wiwynn.com 
8F, 90, Sec.1, Xintai 5th Rd., Xizhi Dist.,
New Taipei City 22102, Taiwan (R.O.C.)
VIA19 
85OHM-8L-1D6MM-L16L18-GP 
P2
N3 GND 4
GND 1
C291 0.22uF 10V 10% 0201 X5R 1 2
C295 0.22uF 10V 10% 0201 X5R 1 2
VIA24 
85OHM-8L-1D6MM-L16L18-GP 
P2
N3 GND 4
GND 1
R569 
51R2F-2-GP 
51 ohm 
1/16W 
1% 
0402 
NOPOP 
1 2
VIA23 
85OHM-8L-1D6MM-L16L18-GP 
P2
N3 GND 4
GND 1
C296 0.22uF 10V 10% 0201 X5R 1 2
C301 0.22uF 10V 10% 0201 X5R 1 2
C289 0.22uF 10V 10% 0201 X5R 1 2
VIA22 
85OHM-8L-1D6MM-L16L18-GP 
P2
N3 GND 4
GND 1
R570 
51R2F-2-GP 
51 ohm 
1/16W 
1% 
0402 
NOPOP 
1 2
C302 0.22uF 10V 10% 0201 X5R 1 2
VIA21 
85OHM-8L-1D6MM-L16L18-GP 
P2
N3 GND 4
GND 1
C293 0.22uF 10V 10% 0201 X5R 1 2
C292 0.22uF 10V 10% 0201 X5R 1 2
C299 0.22uF 10V 10% 0201 X5R 1 2
C304 0.22uF 10V 10% 0201 X5R 1 2
VIA17 
85OHM-8L-1D6MM-L16L18-GP 
P2
N3 GND 4
GND 1
C303 0.22uF 10V 10% 0201 X5R 1 2
VIA26 
85OHM-8L-1D6MM-L16L18-GP 
P2
N3 GND 4
GND 1
C297 0.22uF 10V 10% 0201 X5R 1 2
C300 0.22uF 10V 10% 0201 X5R 1 2
VIA18 
85OHM-8L-1D6MM-L16L18-GP 
P2
N3 GND 4
GND 1
1 OF 14 U1A 
SAS3008C0-1-DB-500020657-1-GP 
PCE_REF_CLK AK4 
PCE_REF_CLK# AK5 
PCE_RX0 AK7 
PCE_RXN0 AJ7 
PCE_RX1 AK8 
PCE_RXN1 AJ8 
PCE_RX2 AK10 
PCE_RXN2 AJ10 
PCE_RX3 AK11 
PCE_RXN3 AJ11 
PCE_RX4 AK13 
PCE_RXN4 AJ13 
PCE_RX5 AK14 
PCE_RXN5 AJ14 
PCE_RX6 AK16 
PCE_RXN6 AJ16 
PCE_RX7 AK17 
PCE_RXN7 AJ17 
PCE_RST_OUT# AJ19 
PCE_TX0 AG7 
PCE_TXN0 AF7 
PCE_TX1 AG8 
PCE_TXN1 AF8 
PCE_TX2 AG10 
PCE_TXN2 AF10 
PCE_TX3 AG11 
PCE_TXN3 AF11 
PCE_TX4 AG13 
PCE_TXN4 AF13 
PCE_TX5 AG14 
PCE_TXN5 AF14 
PCE_TX6 AG16 
PCE_TXN6 AF16 
PCE_TX7 AG17 
PCE_TXN7 AF17 
C290 0.22uF 10V 10% 0201 X5R 1 2
VIA20 
85OHM-8L-1D6MM-L16L18-GP 
P2
N3 GND 4
GND 1
C294 0.22uF 10V 10% 0201 X5R 1 2
C298 0.22uF 10V 10% 0201 X5R 1 2



5
5
4
4
3
3
2
2
1
1
D D
C C
B B
A A
PHY_CON_A_TO_IOC_1_DN 
PHY_CON_A_TO_IOC_1_DP 
PHY_CON_A_TO_IOC_2_DN 
PHY_CON_A_TO_IOC_2_DP 
PHY_CON_A_TO_IOC_3_DN 
PHY_CON_A_TO_IOC_3_DP 
PHY_CON_B_TO_IOC_0_DN 
PHY_CON_B_TO_IOC_0_DP 
PHY_CON_B_TO_IOC_1_DN 
PHY_CON_B_TO_IOC_1_DP 
PHY_CON_B_TO_IOC_2_DN 
PHY_CON_B_TO_IOC_2_DP 
PHY_CON_B_TO_IOC_3_DN 
PHY_CON_B_TO_IOC_3_DP 
PHY_CON_A_TO_IOC_0_DP 
PHY_CON_A_TO_IOC_0_DN 
PHY_IOC_TO_CON_A_0_DP 
PHY_IOC_TO_CON_A_0_DN 
PHY_IOC_TO_CON_A_1_DP 
PHY_IOC_TO_CON_A_1_DN 
PHY_IOC_TO_CON_A_2_DN 
PHY_IOC_TO_CON_A_2_DP 
PHY_IOC_TO_CON_A_3_DP 
PHY_IOC_TO_CON_A_3_DN 
PHY_IOC_TO_CON_B_0_DP 
PHY_IOC_TO_CON_B_0_DN 
PHY_IOC_TO_CON_B_1_DN 
PHY_IOC_TO_CON_B_1_DP 
PHY_IOC_TO_CON_B_2_DN 
PHY_IOC_TO_CON_B_2_DP 
PHY_IOC_TO_CON_B_3_DN 
PHY_IOC_TO_CON_B_3_DP 
IOC_REF_CLK_N 
PHY_IOC_TO_CON_A_1_DP_C 
PHY_IOC_TO_CON_A_1_DN_C 
PHY_IOC_TO_CON_A_2_DP_C 
PHY_IOC_TO_CON_A_2_DN_C 
PHY_IOC_TO_CON_A_3_DP_C 
PHY_IOC_TO_CON_A_3_DN_C 
PHY_IOC_TO_CON_B_0_DP_C 
PHY_IOC_TO_CON_B_0_DN_C 
PHY_IOC_TO_CON_B_1_DP_C 
PHY_IOC_TO_CON_B_1_DN_C 
PHY_IOC_TO_CON_B_2_DP_C 
PHY_IOC_TO_CON_B_2_DN_C 
PHY_IOC_TO_CON_B_3_DP_C 
PHY_IOC_TO_CON_B_3_DN_C 
PHY_IOC_TO_CON_A_0_DP_C 
PHY_IOC_TO_CON_A_0_DN_C 
IOC_REF_CLK_P IOC_CLK_SEL0 
IOC_REF_CLK_N REF_CLK 
IOC_REF_CLK_P 
IOC_CLK_SEL1 
IOC_CLK_SEL0 IOC_CLK_SEL1 
P1V8 
PHY_CON_A_TO_IOC_1_DN 45 
PHY_CON_A_TO_IOC_1_DP 45 
PHY_CON_A_TO_IOC_2_DN 45 
PHY_CON_A_TO_IOC_2_DP 45 
PHY_CON_A_TO_IOC_3_DN 45 
PHY_CON_A_TO_IOC_3_DP 45 
PHY_CON_B_TO_IOC_0_DN 45 
PHY_CON_B_TO_IOC_0_DP 45 
PHY_CON_B_TO_IOC_1_DP 45 
PHY_CON_B_TO_IOC_1_DN 45 
PHY_CON_B_TO_IOC_2_DP 45 
PHY_CON_B_TO_IOC_2_DN 45 
PHY_CON_B_TO_IOC_3_DP 45 
PHY_CON_B_TO_IOC_3_DN 45 
PHY_CON_A_TO_IOC_0_DP 45 
PHY_CON_A_TO_IOC_0_DN 45 
PHY_IOC_TO_CON_A_1_DP 45 
PHY_IOC_TO_CON_A_1_DN 45 
PHY_IOC_TO_CON_A_2_DP 45 
PHY_IOC_TO_CON_A_2_DN 45 
PHY_IOC_TO_CON_A_3_DP 45 
PHY_IOC_TO_CON_A_3_DN 45 
PHY_IOC_TO_CON_B_0_DP 45 
PHY_IOC_TO_CON_B_0_DN 45 
PHY_IOC_TO_CON_B_1_DP 45 
PHY_IOC_TO_CON_B_1_DN 45 
PHY_IOC_TO_CON_B_2_DP 45 
PHY_IOC_TO_CON_B_2_DN 45 
PHY_IOC_TO_CON_B_3_DP 45 
PHY_IOC_TO_CON_B_3_DN 45 
PHY_IOC_TO_CON_A_0_DP 45 
PHY_IOC_TO_CON_A_0_DN 45 
Title 
Size Document Number Rev
Date: Sheet 
of 
Bryce Canyon_IO Module 2
SAS3008_PCIE & SAS 
A3 
37 47Friday, December 08, 2017 
Bryce Canyon_IO Module 
http://www.wiwynn.com 
8F, 90, Sec.1, Xintai 5th Rd., Xizhi Dist.,
New Taipei City 22102, Taiwan (R.O.C.)
Title 
Size Document Number Rev
Date: Sheet 
of 
Bryce Canyon_IO Module 2
SAS3008_PCIE & SAS 
A3 
37 47Friday, December 08, 2017 
Bryce Canyon_IO Module 
http://www.wiwynn.com 
8F, 90, Sec.1, Xintai 5th Rd., Xizhi Dist.,
New Taipei City 22102, Taiwan (R.O.C.)
Title 
Size Document Number Rev
Date: Sheet 
of 
Bryce Canyon_IO Module 2
SAS3008_PCIE & SAS 
A3 
37 47Friday, December 08, 2017 
Bryce Canyon_IO Module 
http://www.wiwynn.com 
8F, 90, Sec.1, Xintai 5th Rd., Xizhi Dist.,
New Taipei City 22102, Taiwan (R.O.C.)
C321 0.01uF 16V 10% 0201 X7R 1 2
C316 0.01uF 16V 10% 0201 X7R 1 2
C311 0.01uF 16V 10% 0201 X7R 1 2
R571 0R2J-2-GP 
0 ohm 1/16W 5% 0402 
1 2
2 OF 14 U1B 
SAS3008C0-1-DB-500020657-1-GP 
SAS_REF_CLK P1 
SAS_REF_CLK# P2 
SAS_RX0 AH4 
SAS_RXN0 AH5 
SAS_RX1 AG4 
SAS_RXN1 AG5 
SAS_RX2 AE4 
SAS_RXN2 AE5 
SAS_RX3 AD4 
SAS_RXN3 AD5 
SAS_RX4 AB4 
SAS_RXN4 AB5 
SAS_RX5 AA4 
SAS_RXN5 AA5 
SAS_RX6 W4 
SAS_RXN6 W5 
SAS_RX7 V4 
SAS_RXN7 V5 
SAS_CLK_SEL0 P29 
SAS_CLK_SEL1 T28 
SAS_TX0 AH1 
SAS_TXN0 AH2 
SAS_TX1 AG1 
SAS_TXN1 AG2 
SAS_TX2 AE1 
SAS_TXN2 AE2 
SAS_TX3 AD1 
SAS_TXN3 AD2 
SAS_TX4 AB1 
SAS_TXN4 AB2 
SAS_TX5 AA1 
SAS_TXN5 AA2 
SAS_TX6 W1 
SAS_TXN6 W2 
SAS_TX7 V1 
SAS_TXN7 V2 C322 0.01uF 16V 10% 0201 X7R 1 2
VIA47 
100OHM-8L-1D6MM-L18L16-GP 
P2
N3 GND 4
GND 1
C305 
SC12P50V2JN-3GP 
12pF 
50V 
5% 
0402 
NPO 
1 2
VIA41 
100OHM-8L-1D6MM-L18L16-GP 
P2
N3 GND 4
GND 1
R572 
10KR2F-2-GP 
10k ohm 
1/16W 
1% 
0402 
12
C320 0.01uF 16V 10% 0201 X7R 1 2
VIA44 
100OHM-8L-1D6MM-L18L16-GP 
P2
N3 GND 4
GND 1
C314 0.01uF 16V 10% 0201 X7R 1 2
R573 
10KR2F-2-GP 
10k ohm 
1/16W 
1% 
0402 
12
C309 0.01uF 16V 10% 0201 X7R 1 2
C315 0.01uF 16V 10% 0201 X7R 1 2
C313 0.01uF 16V 10% 0201 X7R 1 2
VIA48 
100OHM-8L-1D6MM-L18L16-GP 
P2
N3 GND 4
GND 1
C319 0.01uF 16V 10% 0201 X7R 1 2
VIA43 
100OHM-8L-1D6MM-L18L16-GP 
P2
N3 GND 4
GND 1
C308 0.01uF 16V 10% 0201 X7R 1 2
R574 
10KR2F-2-GP 
10k ohm 
1/16W 
1% 
0402 
NOPOP 
12
C307 0.01uF 16V 10% 0201 X7R 1 2
VIA45 
100OHM-8L-1D6MM-L18L16-GP 
P2
N3 GND 4
GND 1
C317 0.01uF 16V 10% 0201 X7R 1 2
VIA42 
100OHM-8L-1D6MM-L18L16-GP 
P2
N3 GND 4
GND 1
R575 
10KR2F-2-GP 
10k ohm 
1/16W 
1% 
0402 
NOPOP 
12
C318 0.01uF 16V 10% 0201 X7R 1 2
C306 
SC12P50V2JN-3GP 
12pF 
50V 
5% 
0402 
NPO 
1 2
C312 0.01uF 16V 10% 0201 X7R 1 2
SX1 
XTAL-25MHZ-295-GP 
4 1
23
VIA46 
100OHM-8L-1D6MM-L18L16-GP 
P2
N3 GND 4
GND 1
C310 0.01uF 16V 10% 0201 X7R 1 2



5
5
4
4
3
3
2
2
1
1
D D
C C
B B
A A
USB 
Ethernet 
SBL_SDA 
IOC_EEPROM_WP 
IOC_EEPROM_A0 
SBL_SCL 
IOC_EEPROM_A1 
IOC_EEPROM_A2 
IOC_SDA_4 
IOC_SCL_4 
IOC_GPIO_20 
IOC_GPIO_0 
IOC_GPIO_21 
SBL_SDA 
SBL_SCL 
IOC_GPIO_22 
IOC_GPIO_23 
IOC_GPIO_24 
IOC_GPIO_25 
IOC_GPIO_26 
IOC_GPIO_27 
IOC_GPIO_28 
IOC_GPIO_29 
IOC_GPIO_30 
IOC_GPIO_31 
IOC_GPIO_32 
IOC_GPIO_33 
IOC_GPIO_34 
IOC_GPIO_35 
IOC_SDA_0 
IOC_SCL_0 
IOC_GPIO_1 
IOC_GPIO_2 
IOC_GPIO_3 
IOC_GPIO_4 
IOC_GPIO_5 
IOC_GPIO_6 
IOC_GPIO_7 
IOC_GPIO_8 
IOC_GPIO_9 
IOC_GPIO_10 
IOC_GPIO_11 
IOC_GPIO_12 
IOC_GPIO_13 
IOC_GPIO_14 
IOC_GPIO_15 
IOC_GPIO_16 
SIO_DIN_0 
SIO_DOUT_0 
SIO_LOAD_0 
SIO_CLK_1 
SIO_DIN_1 
SIO_DOUT_1 
SIO_LOAD_1 
IOC_GPIO_17 
IOC_GPIO_18 
IOC_GPIO_19 
IOC_SIO_BLINK 
SIO_CLK_0 
IOC_SCL_1 
IOC_SDA_1 
IOC_SCL_2 
IOC_SDA_2 
IOC_SCL_3 
IOC_SDA_3 SIO_DIN_1 
SIO_CLK_1 
SIO_LOAD_1 
SIO_DOUT_1 
SIO_DIN_0 
SIO_CLK_0 
SIO_LOAD_0 
SIO_DOUT_0 
SBL_SDA 
IOC_SDA_3 
IOC_SCL_3 
SBL_SCL 
IOC_SDA_4 
IOC_SCL_4 
IOC_SDA_0 
IOC_SCL_0 
IOC_SDA_1 
IOC_SCL_1 
IOC_SDA_2 
IOC_SCL_2 
IOC_EEPROM_SCL 
IOC_EEPROM_SDA 
IOC_EXT2_LED_Y 
IOC_EXT1_LED_Y 
IOC_EXT1_LED_B 
IOC_EXT2_LED_B 
P1V8 P1V8 
P1V8 
IOC_SDA_4 44 
IOC_SCL_4 44 
IOC_EXT1_LED_B 46 
IOC_EXT2_LED_B 46 
IOC_EXT1_LED_Y 46 
IOC_EXT2_LED_Y 46 
Title 
Size Document Number Rev
Date: Sheet 
of 
Bryce Canyon_IO Module 2
SAS3008_GPIO&USB&ETH 
A3 
38 47Friday, December 08, 2017 
Bryce Canyon_IO Module 
http://www.wiwynn.com 
8F, 90, Sec.1, Xintai 5th Rd., Xizhi Dist.,
New Taipei City 22102, Taiwan (R.O.C.)
Title 
Size Document Number Rev
Date: Sheet 
of 
Bryce Canyon_IO Module 2
SAS3008_GPIO&USB&ETH 
A3 
38 47Friday, December 08, 2017 
Bryce Canyon_IO Module 
http://www.wiwynn.com 
8F, 90, Sec.1, Xintai 5th Rd., Xizhi Dist.,
New Taipei City 22102, Taiwan (R.O.C.)
Title 
Size Document Number Rev
Date: Sheet 
of 
Bryce Canyon_IO Module 2
SAS3008_GPIO&USB&ETH 
A3 
38 47Friday, December 08, 2017 
Bryce Canyon_IO Module 
http://www.wiwynn.com 
8F, 90, Sec.1, Xintai 5th Rd., Xizhi Dist.,
New Taipei City 22102, Taiwan (R.O.C.)
R578 2.2k ohm 0402 1 2
TP126 1
TP96 1
TP100 1
TP104 1 TP103 1
TP129 1
TP92 1
R584 2.2k ohm 0402 1 2
TP90 1
TP99 1
TP111 1
R602 0R2J-2-GP 
0 ohm 1/16W 5% 0402 
1 2
R585 2.2k ohm 0402 1 2
TP95 1
TP97 1
R579 2.2k ohm 0402 1 2
R595 2.2k ohm 0402 1 2
TP91 1
U38 
CAT24C64WI-GT3-GP 
A0 1
A1 2
A2 3
VSS 4 SDA 5SCL 6WP 7VCC 8
R605 
4K7R2F-GP 
4.7k ohm 
1/16W 
1% 
0402 
1 2
TP106 1
TP93 1
R600 
4K7R2F-GP 
NOPOP 4.7k ohm 
1/16W 
1% 
0402 
1 2
TP123 1
C323 
SCD1U16V2KX-3GP 
0.1uF 
16V 
10% 
0402 
X7R 
1 2
R581 2.2k ohm 0402 1 2
TP121 1
4 OF 14 U1D 
SAS3008C0-1-DB-500020657-1-GP 
ULPI0_DATA0 D3 
ULPI0_DATA1 A2 
ULPI0_DATA2 C2 
ULPI0_DATA3 C3 
ULPI0_DATA4 P5 
ULPI0_DATA5 P6 
ULPI0_DATA6 F2 
ULPI0_DATA7 E2 
ULPI0_CLK E3 
ULPI0_DIR R7 
ULPI0_NXT B2 
ULPI0_STP N6 
ENET_RXD0 L3 
ENET_RXD1 H3 
ENET_RXD2 H6 
ENET_RXD3 K6 
ENET_RXD4 F9 
ENET_RXD5 F10 
ENET_RXD6 F3 
ENET_RXD7 F7 
ENET_COL D1 
ENET_CRS J3 
ENET_IN_CLK B5 
ENET_MDINT# C1 
ENET_RXCLK H1 
ENET_RXDV J6 
ENET_RXER J2 
ULPI1_DATA0 B10 
ULPI1_DATA1 N5 
ULPI1_DATA2 B4 
ULPI1_DATA3 A5 
ULPI1_DATA4 A3 
ULPI1_DATA5 C4 
ULPI1_DATA6 B3 
ULPI1_DATA7 B1 
ULPI1_CLK A4 
ULPI1_DIR B6 
ULPI1_NXT C5 
ULPI1_STP A7 
ENET_TXD0 G6 
ENET_TXD1 G3 
ENET_TXD2 F1 
ENET_TXD3 G2 
ENET_TXD4 F6 
ENET_TXD5 F8 
ENET_TXD6 C9 
ENET_TXD7 C10 
ENET_GTXCLK J1 
ENET_MDC H2 
ENET_MDIO D2 
ENET_TXCLK K3 
ENET_TXEN E1 
ENET_TXER G1 
TP112 1
TP98 1
TP94 1
TP115 1
TP122 1
TP102 1
TP114 1
3 OF 14 U1C 
SAS3008C0-1-DB-500020657-1-GP 
SBL_SCL T30 
SBL_SDA N30 
IIC0_SCL V29 
IIC0_SDA R29 
IIC1_SCL P30 
IIC1_SDA V30 
IIC2_SCL V28 
IIC2_SDA Y28 
IIC3_SCL P28 
IIC3_SDA U29 
IIC4_SCL W29 
IIC4_SDA R28 
SIO0_CLK M1 
SIO0_DIN T6 
SIO0_DOUT K2 
SIO0_LOAD M3 
SIO1_CLK L1 
SIO1_DIN L2 
SIO1_DOUT M2 
SIO1_LOAD K1 
SIO_BLINK R5 
GPIO0 AF29 
GPIO1 AJ26 
GPIO2 AH22 
GPIO3 AH23 
GPIO4 AJ30 
GPIO5 AH24 
GPIO6 AH25 
GPIO7 AE21 
GPIO8 AC30 
GPIO9 AK29 
GPIO10 AH28 
GPIO11 AH30 
GPIO12 AJ29 
GPIO13 AJ25 
GPIO14 AJ27 
GPIO15 Y30 
GPIO16 AF30 
GPIO17 AD30 
GPIO18 AG29 
GPIO19 AK28 
GPIO20 AJ28 
GPIO21 AG30 
GPIO22 AH29 
GPIO23 AB29 
GPIO24 W30 
GPIO25 AG28 
GPIO26 AF28 
GPIO27 AD29 
GPIO28 AC28 
GPIO29 AD28 
GPIO30 AC29 
GPIO31 AE30 
GPIO32 N28 
GPIO33 AA29 
GPIO34 AB28 
GPIO35 AB30 
GPIO36 AA28 
GPIO37 AA30 
GPIO38 W28 
GPIO39 AE29 
R592 2.2k ohm 0402 1 2
R590 2.2k ohm 0402 1 2
TP105 1
R598 
10KR2F-2-GP 
10k ohm 
1/16W 
1% 
0402 
1 2
R608 0R2J-2-GP 
0 ohm 1/16W 5% 0402 
1 2
TP125 1
TP119 1
TP85 1
TP120 1
R588 2.2k ohm 0402 1 2
TP88 1
R576 2.2k ohm 0402 1 2
R583 2.2k ohm 0402 1 2
R577 2.2k ohm 0402 1 2
TP113 1
TP128 1
R593 2.2k ohm 0402 1 2
TP110 1
R604 
4K7R2F-GP 
4.7k ohm 
1/16W 
1% 
0402 
1 2
TP89 1
R589 2.2k ohm 0402 1 2
TP127 1
R580 2.2k ohm 0402 1 2
TP107 1
TP108 1
R603 
4K7R2F-GP 
4.7k ohm 
1/16W 
1% 
0402 
1 2
R594 2.2k ohm 0402 1 2
R591 2.2k ohm 0402 1 2
R586 2.2k ohm 0402 1 2
TP86 1
R582 2.2k ohm 0402 1 2
R606 0R2J-2-GP 
0 ohm 1/16W 5% 0402 
1 2
R587 2.2k ohm 0402 1 2
TP124 1
TP116 1
TP118 1TP117 1
TP109 1
TP87 1
TP101 1



5
5
4
4
3
3
2
2
1
1
D D
C C
B B
A A
AVSO_IDDTN18 
SYS_RST_N_0 
SYS_RST_N_1 
SYS_CORE_TRI# 
POWERLOSS# 
CP_DONE 
MEM_CLK_SEL 
RTRIM# 
RTRIM 
SYS_HB_LED 
SYS_ERR_0 
SYS_DBMODE0 
SYS_DBMODE1 
SYS_DBMODE2 
SYS_DBMODE3 
SYS_DBMODE4 
LSI_JTAG_EN_N 
LSI_SCAN_EN 
LSI_TN 
LSI_IDDT 
SYS_DBMODE1 
SYS_DBMODE2 
SYS_DBMODE3 
LSI_IDDT 
SYS_DBMODE4 
SYS_DBMODE0 
LSI_SCAN_EN 
ICE0_TCK 
ICE0_TMS 
ICE0_TDI 
ICE0_TDO 
ICE0_TRST# 
ICE_SEL 
ICE1_TCK 
ICE1_TMS 
ICE1_TDI 
ICE1_TDO 
ICE1_TRST# 
SYS_HALT0# 
SYS_HALT1# 
ICE1_TCK 
ICE1_TMS 
ICE1_TDI 
ICE1_TRST# 
ICE0_TRST# 
SYS_HALT1# 
ICE0_TDI 
ICE0_TCK 
ICE0_TMS 
ICE_SEL 
SYS_HB_LED_D 
SYS_HB_LED_R 
SYS_ERROR_LED_D
SYS_ERROR_LED_R
SPARE0 
SPARE1 
SPARE2 
SPARE3 
SPARE4 
SPARE5 
IOC_UART_1_RX 
IOC_UART_1_TX 
UART_SERCLK 
UART_SERCLK 
IOC_UART_1_RX 
IOC_UART_0_RX 
OSC_REF_CLK 
IOC_RESET# 
SYS_HALT0# 
IOC_TRST_N 
IOC_UART_0_RX 
IOC_UART_0_TX 
SYS_ERROR1 
P3V3_STBY_G 
PCIE_COMP_TO_IOM_RST_2 
SYS_RST_N_0 
IOC_TDO 
JTAG_IOC_TCK 
JTAG_IOC_TMS 
JTAG_IOC_TDI 
IOC_TRST_N 
CP_DONE 
SYS_CORE_TRI# 
POWERLOSS# 
SYS_RST_N_1 
LSI_JTAG_EN_N 
LSI_TN 
SYS_HB_LED SYS_ERR_0 
IOC_VREF_SET 
IOC_VREF_SET 
PWRGD_P0V975 IOC_RESET# 
P1V8 
P1V8 
P3V3 
P1V8 
P1V8 
P3V3_STBY 
P3V3 
P1V8 
P1V8 
P1V8_STBY P1V8 
PWRGD_P1V8 34 
PWRGD_P0V975 35 
IOC_UART_0_RX 44 
IOC_UART_0_TX 44 
AVSO_VREF 35 
PCIE_COMP_TO_IOM_RST_2 11 
SYS_RST_N_0 44
Title 
Size Document Number Rev
Date: Sheet 
of 
Bryce Canyon_IO Module 2
SAS3008_MISC 
A3 
39 47Friday, December 08, 2017 
Bryce Canyon_IO Module 
http://www.wiwynn.com 
8F, 90, Sec.1, Xintai 5th Rd., Xizhi Dist.,
New Taipei City 22102, Taiwan (R.O.C.)
Title 
Size Document Number Rev
Date: Sheet 
of 
Bryce Canyon_IO Module 2
SAS3008_MISC 
A3 
39 47Friday, December 08, 2017 
Bryce Canyon_IO Module 
http://www.wiwynn.com 
8F, 90, Sec.1, Xintai 5th Rd., Xizhi Dist.,
New Taipei City 22102, Taiwan (R.O.C.)
Title 
Size Document Number Rev
Date: Sheet 
of 
Bryce Canyon_IO Module 2
SAS3008_MISC 
A3 
39 47Friday, December 08, 2017 
Bryce Canyon_IO Module 
http://www.wiwynn.com 
8F, 90, Sec.1, Xintai 5th Rd., Xizhi Dist.,
New Taipei City 22102, Taiwan (R.O.C.)
R619 
4K7R2F-GP 
4.7k ohm 
1/16W 
1% 
0402 
1 2
Q15 
SSM3K324R-GP 
S
G
D
R659 
4K7R2F-GP 
4.7k ohm 
1/16W 
1% 
0402 
1 2
R649 
10KR2F-2-GP 
10k ohm 
1/16W 
1% 
0402 
1 2
R655 
10KR2F-2-GP 
10k ohm 
1/16W 
1% 
0402 
1 2
R645 
10KR2F-2-GP 
10k ohm 
1/16W 
1% 
0402 
1 2
R641 
4K7R2F-GP 
NOPOP 
4.7k ohm 
1/16W 
1% 
0402 
1 2
C327 
SCD1U16V2KX-3GP 
0.1uF 
16V 
10% 
0402 
X7R 
1 2
R650 
10KR2F-2-GP 
10k ohm 
1/16W 
1% 
0402 
1 2
R639 
4K7R2F-GP 
4.7k ohm 
1/16W 
1% 
0402 
12
R640 
4K7R2F-GP 
NOPOP 
4.7k ohm 
1/16W 
1% 
0402 
1 2
TP161 1
TP153 1
Q16 
2N7002K-1-GP 
G
D S
R632 
4K7R2F-GP 
4.7k ohm 
1/16W 
1% 
0402 
1 2
TP130 1
TP142 1
TP133 1
R626 
10KR2F-2-GP 
10k ohm 
1/16W 
1% 
0402 
1 2
TP136 1
TP138 1
TP140 1
R635 
4K7R2F-GP 
4.7k ohm 
1/16W 
1% 
0402 
1 2
TP135 1
Q17 
2N7002K-1-GP 
G
D S
R629 
4K7R2F-GP 
4.7k ohm 
1/16W 
1% 
0402 
1 2
R652 
10KR2F-2-GP 
10k ohm 
1/16W 
1% 
0402 
1 2
TP157 1
TP151 1
R656 
10KR2F-2-GP 
10k ohm 
1/16W 
1% 
0402 
1 2
TP158 1
R653 
10KR2F-2-GP 
10k ohm 
1/16W 
1% 
0402 
1 2
TP154 1
R644 
4K7R2F-GP 
NOPOP 
4.7k ohm 
1/16W 
1% 
0402 
1 2
TP147 1
TP155 1
Q14 
SSM3K324R-GP
S
G
D
LED4 
LED-YG-51-GP
A K
TP134 1
R637 
4K7R2F-GP 
4.7k ohm 
1/16W 
1% 
0402 
1 2
U41 
TPS3808G18DRVT-GP-U 
VDD 1
SENSE 2
CT 3
MR# 4 GND 5 RESET# 6 GND 7
TP139 1
R616 
4K7R2F-GP 
4.7k ohm 
1/16W 
1% 
0402 
1 2
R642 
4K7R2F-GP 
NOPOP 
4.7k ohm 
1/16W 
1% 
0402 
1 2
R633 
4K7R2F-GP 
4.7k ohm 
1/16W 
1% 
0402 
1 2
R628 
4K7R2F-GP 
4.7k ohm 
1/16W 
1% 
0402 
1 2
TP156 1
R624 10KR2F-2-GP 
10k ohm 1/16W 1% 0402 
1 2
TP145 1
R634 
4K7R2F-GP 
4.7k ohm 
1/16W 
1% 
0402 
1 2
TP146 1
6 OF 14 U1F 
SAS3008C0-1-DB-500020657-1-GP 
AVSO_VREF B13 
AVSO_IDDTN18 B12 
AVSO_PGIO18 C12 
AVSO_PGCORE18 A13 
PG_CORE A12 
VREF_SET B9 
SYS_PWR_ON_RST# AJ21 
SYS_RST0# AH20 
SYS_RST1# AE23 
MSS_PWR_ON_RST# U28 
SYS_CORE_TRI# R30 
POWERLOSS# R6 
CP_DONE U30 
MEM_CLK_SEL N29 
SYS_RTRIM T1 
SYS_RTRIM# T2 
SYS_HB_LED T29 
SYS_ERROR0 AJ20 
SYS_ERROR1 AK22 
SYS_DBMODE0 AE22 
SYS_DBMODE1 AK20 
SYS_DBMODE2 AK24 
SYS_DBMODE3 AJ23 
SYS_DBMODE4 AK21 
SYSTEM_JTAG_ENABLE# B16 
LSI_SCAN_ENABLE B17 
LSI_TN C16 
LSI_IDDT A18 
SPARE0 AH27 
SPARE1 AK25 
SPARE2 AJ22 
SPARE3 AE20 
SPARE4 Y29 
SPARE5 AE19 
UART0_RX AJ24 
UART0_TX AK27 
UART1_RX AH26 
UART1_TX AH21 
UART_SERCLK AE28 
ICE_SEL M6 
ICE0_TCK A9 
ICE0_TMS C7 
ICE0_TDI B8 
ICE0_TDO C8 
ICE0_TRST# A8 
ICE1_TCK B7 
ICE1_TMS A6 
ICE1_TDI L6 
ICE1_TDO A10 
ICE1_TRST# C6 
SYS_HALT0# AK23 
SYS_HALT1# AK26 
LSI_TCK C17 
LSI_TMS B18 
LSI_TDI A17 
LSI_TDO C18 
LSI_TRST# A16 
OSC_OUT_REF_CLK T4 
TST_VREFPSENSE C13 
NC#AH19 AH19 
NC#AK19 AK19 
TP152 1
LED5 
LED-YG-51-GP 
A K
R630 
4K7R2F-GP 
4.7k ohm 
1/16W 
1% 
0402 
1 2
TP131 1
R621 
4K7R2F-GP 
4.7k ohm 
1/16W 
1% 
0402 
1 2
R638 
4K7R2F-GP 
4.7k ohm 
1/16W 
1% 
0402 
12
R625 3KR2J-2-GP 
3k ohm 1/16W 5% 0402 
1 2
TP143 1
R623 
150R2F-1-GP 
150 ohm 
1/16W 
1% 
0402 
1 2
R654 
10KR2F-2-GP 
10k ohm 
1/16W 
1% 
0402 
1 2
R648 
10KR2F-2-GP 
10k ohm 
1/16W 
1% 
0402 
1 2
R646 
10KR2F-2-GP 
10k ohm 
1/16W 
1% 
0402 
1 2
TP144 1
R657 
10KR2F-2-GP 
10k ohm 
1/16W 
1% 
0402 
1 2
R636 
4K7R2F-GP 
4.7k ohm 
1/16W 
1% 
0402 
1 2
TP149 1
R627 
4K7R2F-GP 
4.7k ohm 
1/16W 
1% 
0402 
1 2
TP141 1
R658 
4K7R2F-GP 
4.7k ohm 
1/16W 
1% 
0402 
1 2
TP137 1
TP160 1
R622 
150R2F-1-GP 
150 ohm 
1/16W 
1% 
0402
1 2
R647 
10KR2F-2-GP 
10k ohm 
1/16W 
1% 
0402 
1 2
TP159 1
R631 
4K7R2F-GP 
4.7k ohm 
1/16W 
1% 
0402 
1 2
TP150 1
R618 
10KR2F-2-GP 
10k ohm 
1/16W 
1% 
0402 
1 2
R620 
4K7R2F-GP 
4.7k ohm 
1/16W 
1% 
0402 
1 2
R643 
4K7R2F-GP 
NOPOP 
4.7k ohm 
1/16W 
1% 
0402 
1 2
TP148 1



5
5
4
4
3
3
2
2
1
1
D D
C C
B B
A A
XM_ADDR_10 
XM_ADDR_12 
XM_ADDR_13 
XM_ADDR_3 
XM_DATA_0 
XM_ADDR_21 
XM_ADDR_14 
XM_ADDR_25 
XM_ADDR_15 
XM_ADDR_16 
XM_ADDR_24 
XM_ADDR_20 
XM_ADDR_17 
XM_ADDR_18 
XM_ADDR_19 
XM_ADDR_0 
XM_ADDR_1 
XM_ADDR_2 
XM_ADDR_4 
XM_ADDR_5 
XM_ADDR_6 
XM_ADDR_9 
XM_ADDR_8 
XM_ADDR_11 
XM_ADDR_7 
XM_ADDR_22 
XM_ADDR_23 
XM_DATA_1 
XM_DATA_2 
XM_DATA_3 
XM_DATA_4 
XM_DATA_5 
XM_DATA_6 
XM_DATA_7 
XM_DATA_8 
XM_DATA_9 
XM_DATA_10 
XM_DATA_11 
XM_DATA_12 
XM_DATA_13 
XM_DATA_14 
XM_DATA_15 
XM_ALE 
XM_CLE 
XM_WP 
XM_RB 
XM_OE_N 
XM_F_RST_N 
XM_NOR_CS_N 
XM_NAND_CS_N 
XM_CS0_N 
XM_DATA_0 
XM_DATA_1 
XM_DATA_2 
XM_DATA_3 
XM_DATA_15 
XM_DATA_11 
XM_DATA_12 
XM_DATA_13 
XM_DATA_14 
XM_DATA_4 
XM_DATA_5 
XM_DATA_6 
XM_DATA_7 
XM_DATA_8 
XM_DATA_9 
XM_DATA_10 
XM_F_RST_N 
XM_ADDR_1 
XM_ADDR_5 
XM_ADDR_6 
XM_ADDR_7 
XM_ADDR_8 
XM_ADDR_13 
XM_ADDR_14 
XM_ADDR_15 
XM_ADDR_16 
XM_ADDR_9 
XM_ADDR_10 
XM_ADDR_11 
XM_ADDR_12 
XM_ADDR_21 
XM_ADDR_22 
XM_ADDR_23 
XM_ADDR_17 
XM_ADDR_18 
XM_ADDR_19 
XM_ADDR_20 
XM_ADDR_3 
XM_ADDR_4 
XM_ADDR_2 
XM_OE_N 
IOC_WP_N 
XM_WE_N 
XM_RB 
XM_WE_N 
XM_NOR_CS_N 
XM_ADDR_1 
XM_ADDR_11 
XM_OE_N 
BYTE_N 
P1V8 
P1V8 
P3V3_STBY P1V8 
P1V8 
P1V8 
P1V8 P1V8 
P1V8 
P1V8 P1V8 
P1V8 
P1V8 
Title 
Size Document Number Rev
Date: Sheet 
of 
Bryce Canyon_IO Module 2
SAS3008_FLASH 
A3 
40 47Friday, December 08, 2017 
Bryce Canyon_IO Module 
http://www.wiwynn.com 
8F, 90, Sec.1, Xintai 5th Rd., Xizhi Dist.,
New Taipei City 22102, Taiwan (R.O.C.)
Title 
Size Document Number Rev
Date: Sheet 
of 
Bryce Canyon_IO Module 2
SAS3008_FLASH 
A3 
40 47Friday, December 08, 2017 
Bryce Canyon_IO Module 
http://www.wiwynn.com 
8F, 90, Sec.1, Xintai 5th Rd., Xizhi Dist.,
New Taipei City 22102, Taiwan (R.O.C.)
Title 
Size Document Number Rev
Date: Sheet 
of 
Bryce Canyon_IO Module 2
SAS3008_FLASH 
A3 
40 47Friday, December 08, 2017 
Bryce Canyon_IO Module 
http://www.wiwynn.com 
8F, 90, Sec.1, Xintai 5th Rd., Xizhi Dist.,
New Taipei City 22102, Taiwan (R.O.C.)
R766 
10KR2F-2-GP 
NOPOP 
10k ohm 
1/16W 
1% 
0402 
1 2
R671 
10KR2F-2-GP 
10k ohm 
1/16W 
1% 
0402 
1 2
TP166 1
R663 
10KR2F-2-GP 
10k ohm 
1/16W 
1% 
0402 
1 2
R672 
10KR2F-2-GP 
10k ohm 
1/16W 
1% 
0402 
1 2
R670 
10KR2F-2-GP 
NOPOP 
10k ohm 
1/16W 
1% 
0402 
1 2
R767 
10KR2F-2-GP 
NOPOP 
10k ohm 
1/16W 
1% 
0402 
1 2
TP167 1
R669 
10KR2F-2-GP 
10k ohm 
1/16W 
1% 
0402 
1 2
R678 
10KR2F-2-GP 
10k ohm 
1/16W 
1% 
0402 
1 2
R661 
10KR2F-2-GP 
10k ohm 
1/16W 
1% 
0402 
1 2
R660 
10KR2F-2-GP 
10k ohm 
1/16W 
1% 
0402 
1 2
TP162 1
R665 
10KR2F-2-GP 
10k ohm 
1/16W 
1% 
0402 
1 2
5 OF 14 U1E 
SAS3008C0-1-DB-500020657-1-GP 
XM_ADDR0 B25 
XM_ADDR1 B27 
XM_ADDR2 C27 
XM_ADDR3 A26 
XM_ADDR4 A28 
XM_ADDR5 C28 
XM_ADDR6 B28 
XM_ADDR7 B30 
XM_ADDR8 B29 
XM_ADDR9 D28 
XM_ADDR10 D29 
XM_ADDR11 C29 
XM_ADDR12 E28 
XM_ADDR13 C30 
XM_ADDR14 E30 
XM_ADDR15 G28 
XM_ADDR16 F29 
XM_ADDR17 D30 
XM_ADDR18 H30 
XM_ADDR19 F28 
XM_ADDR20 F30 
XM_ADDR21 G29 
XM_ADDR22 J29 
XM_ADDR23 K29 
XM_ADDR24 J30 
XM_ADDR25 H29 
XM_ALE B26 
XM_CLE C23 
XM_WP A25 
XM_RB A22 
XM_DATA0 H28 
XM_DATA1 K30 
XM_DATA2 K28 
XM_DATA3 L30 
XM_DATA4 L29 
XM_DATA5 C22 
XM_DATA6 C20 
XM_DATA7 C24 
XM_DATA8 C21 
XM_DATA9 C26 
XM_DATA10 C25 
XM_DATA11 A29 
XM_DATA12 J28 
XM_DATA13 G30 
XM_DATA14 E29 
XM_DATA15 C19 
XM_OE# B22 
XM_WE# A24 
XM_WBE0# B24 
XM_WBE1# A27 
XM_F_RST# B20 
XM_CS0# B19 
XM_CS1# A23 
XM_CS2# B23 
XM_CS3# A19 
XM_NOR_CS# A21 
XM_NAND_CS# B21 
EXT_GPIO_LATCH# A20 
R677 
10KR2F-2-GP 
10k ohm 
1/16W 
1% 
0402 
1 2
C329 
SCD1U16V2KX-3GP 
0.1uF 
16V 
10% 
0402 
X7R 
1 2
R662 
10KR2F-2-GP 
10k ohm 
1/16W 
1% 
0402 
1 2
R674 
10KR2F-2-GP 
10k ohm 
1/16W 
1% 
0402 
1 2
TP165 1
U42 
S29GL128S10TFIV20-GP 
NC#55 55 
VSS 52 
VCC 43 
VSS 33 
VIO 29 
A0 31 
A1 26 
A2 25 
A3 24 
A4 23 
A5 22 
A6 21 
A7 20 
A8 10 
A9 9
A10 8
A11 7
A12 6
A13 5
A14 4
A15 3
A16 54 
A17 19 
A18 18 
A19 11 
A20 12 
A21 15 
A22 2
NC#1 1
NC#56 56 
DQ0 35 
DQ1 37 
DQ2 39 
DQ3 41 
DQ4 44 
DQ5 46 
DQ6 48 
DQ7 50 
DQ8 36 
DQ9 38 
DQ10 40 
DQ11 42 
DQ12 45 
DQ13 47 
DQ14 49 
DQ15 51 
DNU 28 
RFU#27 27 
RFU#30 30 
RFU#53 53 
OE# 34 
CE# 32 
WE# 13 
WP# 16 
RESET# 14 
RY/BY# 17 
R666
10KR2F-2-GP
10k ohm
1/16W
1%
0402
1 2
TP164 1
R668 
10KR2F-2-GP 
10k ohm 
1/16W 
1% 
0402 
1 2
R747 
10KR2F-2-GP 
10k ohm 
1/16W 
1% 
0402 
1 2
R667 
10KR2F-2-GP 
NOPOP 
10k ohm 
1/16W 
1% 
0402 
1 2
C328 
SCD1U16V2KX-3GP 
0.1uF 
16V 
10% 
0402 
X7R 
1 2
R748 
10KR2F-2-GP 
10k ohm 
1/16W 
1% 
0402 
NOPOP 
1 2
R664 
10KR2F-2-GP 
10k ohm 
1/16W 
1% 
0402 
1 2
TP168 1
R729
10KR2F-2-GP
10k ohm
1/16W
1%
0402
1 2
TP163 1
R673 
10KR2F-2-GP 
10k ohm 
1/16W 
1% 
0402 
1 2
R675 
10KR2F-2-GP 
10k ohm 
1/16W 
1% 
0402 
1 2
R676 
10KR2F-2-GP 
10k ohm 
1/16W 
1% 
0402 
1 2



5
5
4
4
3
3
2
2
1
1
D D
C C
B B
A A
HM40ADC_VDDA 
PLL_VDD 
PCE_VDDH 
VDDIO_15 
SAS0_VDDH 
SHELL_PLL_VDD 
SYS_PLL_VDD 
VDDA_SAS_REF_CLK 
PCE_VDDH 
HM40ADC_VDDA 
P1V8 
P1V8 P1V8 
P1V8 
P1V8 
P1V5 
P1V8 
HM40ADC_VDDA 
PLL_VDD 
SHELL_PLL_VDD 
SYS_PLL_VDD 
VDDA_SAS_REF_CLK 
SAS0_VDDH 
P1V8 
Title 
Size Document Number Rev
Date: Sheet 
of 
Bryce Canyon_IO Module 2
SAS3008_POWER_1 
A3 
41 47Friday, December 08, 2017 
Bryce Canyon_IO Module 
http://www.wiwynn.com 
8F, 90, Sec.1, Xintai 5th Rd., Xizhi Dist.,
New Taipei City 22102, Taiwan (R.O.C.)
Title 
Size Document Number Rev
Date: Sheet 
of 
Bryce Canyon_IO Module 2
SAS3008_POWER_1 
A3 
41 47Friday, December 08, 2017 
Bryce Canyon_IO Module 
http://www.wiwynn.com 
8F, 90, Sec.1, Xintai 5th Rd., Xizhi Dist.,
New Taipei City 22102, Taiwan (R.O.C.)
Title 
Size Document Number Rev
Date: Sheet 
of 
Bryce Canyon_IO Module 2
SAS3008_POWER_1 
A3 
41 47Friday, December 08, 2017 
Bryce Canyon_IO Module 
http://www.wiwynn.com 
8F, 90, Sec.1, Xintai 5th Rd., Xizhi Dist.,
New Taipei City 22102, Taiwan (R.O.C.)
L19 
MPZ2012S601AT-GP 
600Ohm@100MHz 
Imax=2A 
DCR=100mOhm 
Tmax=125C 
12
C357 
SC10U6D3V5KX-4GP 
10uF 
6.3V 
10% 
0805 
X7R 
1 2
L14 
MPZ2012S601AT-GP 
600Ohm@100MHz 
Imax=2A 
DCR=100mOhm 
Tmax=125C 
12
C343 
SC10U6D3V5KX-4GP 
10uF 
6.3V 
10% 
0805 
X7R 
1 2
C349 
SCD1U6D3V1KX-GP 
0.1uF 
6.3V 
10% 
0201 
X5R 
1 2
TP169 1
C356 
SC22U6D3V3MX-9-GP-U 
22uF 
6.3V 
20% 
0603 
X6S 
1 2
C337 
SC1U6D3V1MX-GP 
1uF 
6.3V 
20% 
0201 
X5R 
1 2
C353 
SCD1U6D3V1KX-GP 
0.1uF 
6.3V 
10% 
0201 
X5R 
1 2
C342 
SC22U6D3V3MX-9-GP-U 
22uF 
6.3V 
20% 
0603 
X6S 
1 2
R682 
10R2F-L-GP 
10 ohm 
1/16W 
1% 
0402 
1 2
C354 
SCD1U6D3V1KX-GP 
0.1uF 
6.3V 
10% 
0201 
X5R 
1 2
R685 
10R2F-L-GP 
10 ohm 
1/16W 
1% 
0402 
1 2
C344 
SC1U6D3V1MX-GP 
1uF 
6.3V 
20% 
0201 
X5R 
1 2
C339 
SC10U6D3V5KX-4GP 
10uF 
6.3V 
10% 
0805 
X7R 
1 2
C347 
SC10U6D3V5KX-4GP 
10uF 
6.3V 
10% 
0805 
X7R 
1 2
L17 
MPZ2012S601AT-GP 
600Ohm@100MHz 
Imax=2A 
DCR=100mOhm 
Tmax=125C 
12
C345 
SCD1U6D3V1KX-GP 
0.1uF 
6.3V 
10% 
0201 
X5R 
1 2
C359 
SCD1U6D3V1KX-GP 
0.1uF 
6.3V 
10% 
0201 
X5R 
1 2
7 OF 14 U1G 
SAS3008C0-1-DB-500020657-1-GP 
VDDIO_TOP D16 
VDDIO_TOP D18 
VDDIO_TOP D20 
VDDIO_TOP D22 
VDDIO_TOP D24 
VDDIO_TOP D26 
VDDIO_TOP E15 
VDDIO_TOP E17 
VDDIO_TOP E19 
VDDIO_TOP E21 
VDDIO_RGT_1 D4 
VDDIO_RGT_1 D6 
VDDIO_RGT_1 D8 
VDDIO_RGT_1 D10 
VDDIO_RGT_1 E5 
VDDIO_RGT_1 E7 
VDDIO_RGT_1 E9 
VDDIO_RGT_1 F4 
VDDIO_BOT_1 N27 
VDDIO_BOT_1 P26 
VDDIO_BOT_1 R27 
VDDIO_BOT_1 T26 
VDDIO_BOT_1 U27 
VDDIO_BOT_1 V26 
VDDIO_BOT_1 W27 
VDDIO_BOT_1 Y26 
VDDIO_BOT_1 AA27 
VDDIO_BOT_1 AB26 
VDDIO_BOT_1 AC27 
AVSO_VDDA18 M9 
HM40ADC_VDDA A14 
PLL_VDD AA23 
SHELL_PLL_VDD U10 
SYS_PLL_VDD T9 
VDDA_SAS_REF_CLK V11 
SAS0_VDDH U1 
SAS0_VDDH Y1 
SAS0_VDDH Y6 
SAS0_VDDH AC1 
SAS0_VDDH AC6 
SAS0_VDDH AF1 
SAS0_VDDH AJ1 
VDDIO_TOP E23 
VDDIO_TOP E25 
VDDIO_TOP E27 
VDDIO_TOP F26 
VDDIO_TOP G27 
VDDIO_TOP H26 
VDDIO_TOP J27 
VDDIO_TOP K26 
VDDIO_TOP L27 
VDDIO_RGT_1 G5 
VDDIO_RGT_1 H4 
VDDIO_RGT_1 J5 
VDDIO_RGT_1 K4 
VDDIO_RGT_1 L5 
VDDIO_RGT_1 M4 
VDDIO_RGT_1 N3 
VDDIO_RGT_1 P4 
VDDIO_BOT_1 AD26 
VDDIO_BOT_1 AE27 
VDDIO_BOT_1 AF20 
VDDIO_BOT_1 AF22 
VDDIO_BOT_1 AF24 
VDDIO_BOT_1 AF26 
VDDIO_BOT_1 AG19 
VDDIO_BOT_1 AG21 
VDDIO_BOT_1 AG23 
VDDIO_BOT_1 AG25 
VDDIO_BOT_1 AG27 
VDDIO_15 L22 
PCE_VDDH AE8 
PCE_VDDH AE10 
PCE_VDDH AE12 
PCE_VDDH AE14 
PCE_VDDH AE16 
PCE_VDDH AG9 
PCE_VDDH AG12 
PCE_VDDH AG18 
PCE_VDDH AH15 
C358 
SC1U6D3V1MX-GP 
1uF 
6.3V 
20% 
0201 
X5R 
1 2
C352 
SC1U6D3V1MX-GP 
1uF 
6.3V 
20% 
0201 
X5R 
1 2
C338 
SC22U6D3V3MX-9-GP-U 
22uF 
6.3V 
20% 
0603 
X6S 
1 2
C334 
SC22U6D3V3MX-9-GP-U 
22uF 
6.3V 
20% 
0603 
X6S 
1 2
C360 
SCD1U6D3V1KX-GP 
0.1uF 
6.3V 
10% 
0201 
X5R 
1 2
C351 
SC10U6D3V5KX-4GP 
10uF 
6.3V 
10% 
0805 
X7R 
1 2
L16 
MPZ2012S601AT-GP 
600Ohm@100MHz 
Imax=2A 
DCR=100mOhm 
Tmax=125C 
12
C330 
SC22U6D3V3MX-9-GP-U 
22uF 
6.3V 
20% 
0603 
X6S 
1 2
R683 
10R2F-L-GP 
10 ohm 
1/16W 
1% 
0402 
1 2
C341 
SCD1U6D3V1KX-GP 
0.1uF 
6.3V 
10% 
0201 
X5R 
1 2
R679 
10R2F-L-GP 
10 ohm 
1/16W 
1% 
0402 
1 2
C335 
SC10U6D3V5KX-4GP 
10uF 
6.3V 
10% 
0805 
X7R 
1 2
C333 
SCD1U6D3V1KX-GP 
0.1uF 
6.3V 
10% 
0201 
X5R 
1 2
L18 
MPZ2012S601AT-GP 
600Ohm@100MHz 
Imax=2A 
DCR=100mOhm 
Tmax=125C 
12
R680 
10R2F-L-GP 
10 ohm 
1/16W 
1% 
0402 
1 2
C350 
SC22U6D3V3MX-9-GP-U 
22uF 
6.3V 
20% 
0603 
X6S 
1 2
L15 
MPZ2012S601AT-GP 
600Ohm@100MHz 
Imax=2A 
DCR=100mOhm 
Tmax=125C 
12
C331 
SC10U6D3V5KX-4GP 
10uF 
6.3V 
10% 
0805 
X7R 
1 2
C340 
SC1U6D3V1MX-GP 
1uF 
6.3V 
20% 
0201 
X5R 
1 2
C336 
SCD1U6D3V1KX-GP 
0.1uF 
6.3V 
10% 
0201 
X5R 
1 2
L13 
MPZ2012S601AT-GP 
600Ohm@100MHz 
Imax=2A 
DCR=100mOhm 
Tmax=125C 
12
C346 
SC22U6D3V3MX-9-GP-U 
22uF 
6.3V 
20% 
0603 
X6S 
1 2
C348 
SC1U6D3V1MX-GP 
1uF 
6.3V 
20% 
0201 
X5R 
1 2
C355 
SCD1U6D3V1KX-GP 
0.1uF 
6.3V 
10% 
0201 
X5R 
1 2
C332 
SC10U6D3V5KX-4GP 
10uF 
6.3V 
10% 
0805 
X7R 
1 2
C361 
SCD1U6D3V1KX-GP 
0.1uF 
6.3V 
10% 
0201 
X5R 
1 2
R681 
10R2F-L-GP 
10 ohm 
1/16W 
1% 
0402 
1 2
R684 
10R2F-L-GP 
10 ohm 
1/16W 
1% 
0402 
1 2



5
5
4
4
3
3
2
2
1
1
D D
C C
B B
A A
PCE_AVDD 
SAS0_AVDD 
PCE_AVDD 
P0V975 
P0V975 
SAS0_AVDD 
SAS0_AVDD 
P0V975 
P0V975 P0V975 
P0V975 
P0V975 
Title 
Size Document Number Rev
Date: Sheet 
of 
Bryce Canyon_IO Module 2
SAS3008_POWER_2 
A3 
42 47Friday, December 08, 2017 
Bryce Canyon_IO Module 
http://www.wiwynn.com 
8F, 90, Sec.1, Xintai 5th Rd., Xizhi Dist.,
New Taipei City 22102, Taiwan (R.O.C.)
Title 
Size Document Number Rev
Date: Sheet 
of 
Bryce Canyon_IO Module 2
SAS3008_POWER_2 
A3 
42 47Friday, December 08, 2017 
Bryce Canyon_IO Module 
http://www.wiwynn.com 
8F, 90, Sec.1, Xintai 5th Rd., Xizhi Dist.,
New Taipei City 22102, Taiwan (R.O.C.)
Title 
Size Document Number Rev
Date: Sheet 
of 
Bryce Canyon_IO Module 2
SAS3008_POWER_2 
A3 
42 47Friday, December 08, 2017 
Bryce Canyon_IO Module 
http://www.wiwynn.com 
8F, 90, Sec.1, Xintai 5th Rd., Xizhi Dist.,
New Taipei City 22102, Taiwan (R.O.C.)
C428 
SC1KP50V2KX-1GP 
1000pF 
50V 
10% 
0402 
X7R 
1 2
C426 
SC1KP50V2KX-1GP 
1000pF 
50V 
10% 
0402 
X7R 
1 2
C396 
SCD1U6D3V1KX-GP 
0.1uF 
6.3V 
10% 
0201 
X5R 
1 2
C424 
SC1KP50V2KX-1GP 
1000pF 
50V 
10% 
0402 
X7R 
1 2
C388 
SC10U6D3V5KX-4GP 
10uF 
6.3V 
10% 
0805 
X7R 
1 2
C392 
SC1U16V2KX-7-GP 
1uF 
16V 
10% 
0402 
X6S 
1 2
C367 
SCD1U6D3V1KX-GP 
0.1uF 
6.3V 
10% 
0201 
X5R 
1 2
C418 
SCD1U6D3V1KX-GP 
0.1uF 
6.3V 
10% 
0201 
X5R 
1 2
C389 
SC10U6D3V5KX-4GP 
10uF 
6.3V 
10% 
0805 
X7R 
1 2
C420 
SCD1U6D3V1KX-GP 
0.1uF 
6.3V 
10% 
0201 
X5R 
1 2
L20 
MPZ2012S300AT-GP 
30Ohm@100MHz 
Imax=6A 
DCR=10mOhm 
Tmax=125C 
1 2
L21 
28F0181-1SR-10-GP 
115Ohm@100MHz 
Imax=10A 
DCR=1mOhm 
Tmax=150C 
1 2
C410 
SCD1U6D3V1KX-GP 
0.1uF 
6.3V 
10% 
0201 
X5R 
1 2
C377 
SCD1U6D3V1KX-GP 
0.1uF 
6.3V 
10% 
0201 
X5R 
1 2
8 OF 14 U1H 
SAS3008C0-1-DB-500020657-1-GP 
VDD J12 
VDD K13 
VDD K21 
VDD L14 
VDD L16 
VDD L18 
VDD L20 
VDD M11 
VDD M13 
VDD M15 
VDD M17 
VDD M19 
VDD M21 
VDD N12 
VDD N14 
VDD N16 
VDD N18 
VDD N20 
VDD P13 
VDD P15 
VDD P17 
VDD P19 
VDD P21 
VDD R12 
VDD R14 
PPC_VDD G10 
PPC_VDD H9 
PPC_VDD H11 
PPC_VDD J8 
PPC_VDD J10 
PCIE_AVDD AD9 
PCIE_AVDD AD11 
PCIE_AVDD AD13 
PCIE_AVDD AD15 
PCIE_AVDD AK6 
PCIE_AVDD AK9 
PCIE_AVDD AK12 
PCIE_AVDD AK15 
PCIE_AVDD AK18 
VDDA_PCE_REF_CLK AC11 
VDD R16 
VDD R18 
VDD R20 
VDD T13 
VDD T15 
VDD T17 
VDD T19 
VDD T21 
VDD U12 
VDD U14 
VDD U16 
VDD U18 
VDD U20 
VDD V13 
VDD V15 
VDD V17 
VDD V19 
VDD V21 
VDD W14 
VDD W16 
VDD W18 
VDD W20 
VDD Y17 
VDD Y19 
VDD Y21 
PPC_VDD K9 
PPC_VDD K11 
PPC_VDD L10 
PPC_VDD L12 
SAS0_AVDD AB7 
SAS0_AVDD AC4 
SAS0_AVDD AD7 
SAS0_AVDD AF4 
SAS0_AVDD AJ3 
SAS1_AVDD V7 
SAS1_AVDD V9 
SAS1_AVDD Y4 
SAS1_AVDD Y7 C383 
SCD1U6D3V1KX-GP 
0.1uF 
6.3V 
10% 
0201 
X5R 
1 2
C387 
SC10U6D3V5KX-4GP 
10uF 
6.3V 
10% 
0805 
X7R 
1 2
C373 
SC100U6D3V6MX-GP 
100uF 
6.3V 
20% 
1206 
X5R 
12
R686 
D51R3F-2-GP 
0.51 ohm 
1/10W 
1% 
0603 
1 2
C379 
SCD1U6D3V1KX-GP 
0.1uF 
6.3V 
10% 
0201 
X5R 
1 2
C369 
SCD1U6D3V1KX-GP 
0.1uF 
6.3V 
10% 
0201 
X5R 
1 2
C417 
SCD1U6D3V1KX-GP 
0.1uF 
6.3V 
10% 
0201 
X5R 
1 2
C419 
SCD1U6D3V1KX-GP 
0.1uF 
6.3V 
10% 
0201 
X5R 
1 2
C413 
SCD1U6D3V1KX-GP 
0.1uF 
6.3V 
10% 
0201 
X5R 
1 2
C390 
SC1U16V2KX-7-GP 
1uF 
16V 
10% 
0402 
X6S 
1 2
C409 
SCD1U6D3V1KX-GP 
0.1uF 
6.3V 
10% 
0201 
X5R 
1 2
C401 
SCD1U6D3V1KX-GP 
0.1uF 
6.3V 
10% 
0201 
X5R 
1 2
C371 
SCD1U6D3V1KX-GP 
0.1uF 
6.3V 
10% 
0201 
X5R 
1 2
C427 
SC1KP50V2KX-1GP 
1000pF 
50V 
10% 
0402 
X7R 
1 2
C370 
SCD1U6D3V1KX-GP 
0.1uF 
6.3V 
10% 
0201 
X5R 
1 2
C429 
SC1KP50V2KX-1GP 
1000pF 
50V 
10% 
0402 
X7R 
1 2
C386 
SC10U6D3V5KX-4GP 
10uF 
6.3V 
10% 
0805 
X7R 
1 2
C416 
SCD1U6D3V1KX-GP 
0.1uF 
6.3V 
10% 
0201 
X5R 
1 2
C374 
SC100U6D3V6MX-GP 
100uF 
6.3V 
20% 
1206 
X5R 
12
C399 
SCD1U6D3V1KX-GP 
0.1uF 
6.3V 
10% 
0201 
X5R 
1 2
C364 
SC1U6D3V1MX-GP 
1uF 
6.3V 
20% 
0201 
X5R 
1 2
C412 
SCD1U6D3V1KX-GP 
0.1uF 
6.3V 
10% 
0201 
X5R 
1 2
R687 
D51R3F-2-GP 
0.51 ohm 
1/10W 
1% 
0603 
1 2
C408 
SCD1U6D3V1KX-GP 
0.1uF 
6.3V 
10% 
0201 
X5R 
1 2
C375 
SC1U6D3V1MX-GP 
1uF 
6.3V 
20% 
0201 
X5R 
1 2
C404 
SCD1U6D3V1KX-GP 
0.1uF 
6.3V 
10% 
0201 
X5R 
1 2
C391 
SC1U16V2KX-7-GP 
1uF 
16V 
10% 
0402 
X6S 
1 2
C394 
SC1U16V2KX-7-GP 
1uF 
16V 
10% 
0402 
X6S 
1 2
C397 
SCD1U6D3V1KX-GP 
0.1uF 
6.3V 
10% 
0201 
X5R 
1 2
C363 
SC22U6D3V3MX-9-GP-U 
22uF 
6.3V 
20% 
0603 
X6S 
1 2
C378 
SCD1U6D3V1KX-GP 
0.1uF 
6.3V 
10% 
0201 
X5R 
1 2
C415 
SCD1U6D3V1KX-GP 
0.1uF 
6.3V 
10% 
0201 
X5R 
1 2
C372 
SCD1U6D3V1KX-GP 
0.1uF 
6.3V 
10% 
0201 
X5R 
1 2
C411 
SCD1U6D3V1KX-GP 
0.1uF 
6.3V 
10% 
0201 
X5R 
1 2
C380 
SCD1U6D3V1KX-GP 
0.1uF 
6.3V 
10% 
0201 
X5R 
1 2
C407 
SCD1U6D3V1KX-GP 
0.1uF 
6.3V 
10% 
0201 
X5R 
1 2
C382 
SCD1U6D3V1KX-GP 
0.1uF 
6.3V 
10% 
0201 
X5R 
1 2
C403 
SCD1U6D3V1KX-GP 
0.1uF 
6.3V 
10% 
0201 
X5R 
1 2
C385 
SC10U6D3V5KX-4GP 
10uF 
6.3V 
10% 
0805 
X7R 
1 2
C395 
SC1U16V2KX-7-GP 
1uF 
16V 
10% 
0402 
X6S 
1 2
C393 
SC1U16V2KX-7-GP 
1uF 
16V 
10% 
0402 
X6S 
1 2
C365 
SCD1U6D3V1KX-GP 
0.1uF 
6.3V 
10% 
0201 
X5R 
1 2
C414 
SCD1U6D3V1KX-GP 
0.1uF 
6.3V 
10% 
0201 
X5R 
1 2
C406 
SCD1U6D3V1KX-GP 
0.1uF 
6.3V 
10% 
0201 
X5R 
1 2
C402 
SCD1U6D3V1KX-GP 
0.1uF 
6.3V 
10% 
0201 
X5R 
1 2
C422 
SCD1U6D3V1KX-GP 
0.1uF 
6.3V 
10% 
0201 
X5R 
1 2
C425 
SC1KP50V2KX-1GP 
1000pF 
50V 
10% 
0402 
X7R 
1 2
C376 
SCD1U6D3V1KX-GP 
0.1uF 
6.3V 
10% 
0201 
X5R 
1 2
C368 
SCD1U6D3V1KX-GP 
0.1uF 
6.3V 
10% 
0201 
X5R 
1 2
C400 
SCD1U6D3V1KX-GP 
0.1uF 
6.3V 
10% 
0201 
X5R 
1 2
C430 
SC1KP50V2KX-1GP 
1000pF 
50V 
10% 
0402 
X7R 
1 2
C405 
SCD1U6D3V1KX-GP 
0.1uF 
6.3V 
10% 
0201 
X5R 
1 2
C423 
SC1KP50V2KX-1GP 
1000pF 
50V 
10% 
0402 
X7R 
1 2
C421 
SCD1U6D3V1KX-GP 
0.1uF 
6.3V 
10% 
0201 
X5R 
1 2
C398 
SCD1U6D3V1KX-GP 
0.1uF 
6.3V 
10% 
0201 
X5R 
1 2
C366 
SCD1U6D3V1KX-GP 
0.1uF 
6.3V 
10% 
0201 
X5R 
1 2
C362 
SC100U6D3V6MX-GP 
100uF 
6.3V 
20% 
1206 
X5R 
12
C384 
SC10U6D3V5KX-4GP 
10uF 
6.3V 
10% 
0805 
X7R 
1 2
C381 
SCD1U6D3V1KX-GP 
0.1uF 
6.3V 
10% 
0201 
X5R 
1 2



5
5
4
4
3
3
2
2
1
1
D D
C C
B B
A A
P1V8 
P1V8 
P1V8 
P1V8 
Title 
Size Document Number Rev
Date: Sheet 
of 
Bryce Canyon_IO Module 2
SAS3008_POWER&GND 
A3 
43 47Friday, December 08, 2017 
Bryce Canyon_IO Module 
http://www.wiwynn.com 
8F, 90, Sec.1, Xintai 5th Rd., Xizhi Dist.,
New Taipei City 22102, Taiwan (R.O.C.)
Title 
Size Document Number Rev
Date: Sheet 
of 
Bryce Canyon_IO Module 2
SAS3008_POWER&GND 
A3 
43 47Friday, December 08, 2017 
Bryce Canyon_IO Module 
http://www.wiwynn.com 
8F, 90, Sec.1, Xintai 5th Rd., Xizhi Dist.,
New Taipei City 22102, Taiwan (R.O.C.)
Title 
Size Document Number Rev
Date: Sheet 
of 
Bryce Canyon_IO Module 2
SAS3008_POWER&GND 
A3 
43 47Friday, December 08, 2017 
Bryce Canyon_IO Module 
http://www.wiwynn.com 
8F, 90, Sec.1, Xintai 5th Rd., Xizhi Dist.,
New Taipei City 22102, Taiwan (R.O.C.)
C439 
SCD1U16V2KX-3GP 
0.1uF 
16V 
10% 
0402 
X7R 
1 2
C451 
SCD1U16V2KX-3GP 
0.1uF 
16V 
10% 
0402 
X7R 
1 2
C446 
SCD1U16V2KX-3GP 
0.1uF 
16V 
10% 
0402 
X7R 
1 2
C464 
SC1U16V2KX-7-GP 
1uF 
16V 
10% 
0402 
X6S 
1 2
C471 
SCD1U16V2KX-3GP 
0.1uF 
16V 
10% 
0402 
X7R 
1 2
C473 
SC1KP50V2KX-1GP 
1000pF 
50V 
10% 
0402 
X7R 
1 2
C460 
SCD1U16V2KX-3GP 
0.1uF 
16V 
10% 
0402 
X7R 
1 2
C453 
SCD1U16V2KX-3GP 
0.1uF 
16V 
10% 
0402 
X7R 
1 2
C452 
SCD1U16V2KX-3GP 
0.1uF 
16V 
10% 
0402 
X7R 
1 2
13 OF 14 U1M 
SAS3008C0-1-DB-500020657-1-GP 
VSS AA19 
VSS AA20 
VSS AA21 
VSS AA22 
VSS AA24 
VSS AA25 
VSS AA26 
VSS AB3 
VSS AB6 
VSS AB8 
VSS AB9 
VSS AB10 
VSS AB11 
VSS AB12 
VSS AB13 
VSS AB14 
VSS AB15 
VSS AB16 
VSS AB17 
VSS AB18 
VSS AB19 
VSS AB20 
VSS AB21 
VSS AB22 
VSS AB23 
VSS AB24 
VSS AB25 
VSS AB27 
VSS AC2 
VSS AC3 
VSS AC5 
VSS AC7 
VSS AC8 
VSS AC9 
VSS AC10 
VSS AC12 
VSS AC13 
VSS AC14 
VSS AC15 
VSS AC16 
VSS AC17 
VSS AC18 
VSS AC19 
VSS AC20 
VSS AC21 
VSS AC22 
VSS AC23 
VSS AC24 
VSS AC25 
VSS AC26 
VSS AD3 
VSS AD6 
VSS AD8 
VSS AD10 
VSS AD12 
VSS AD14 
VSS AD16 
VSS AD17 
VSS AD18 
VSS AD19 
VSS AD20 
VSS AD21 
VSS AD22 
VSS AD23 
VSS AD24 
VSS AD25 
VSS AD27 
VSS AE3 
VSS AE6 
VSS AE7 
VSS AE9 
VSS AE11 
VSS AE13 
VSS AE15 
VSS AE17 
VSS AE18 
VSS AE24 
VSS AE25 
C476 
SC1KP50V2KX-1GP 
1000pF 
50V 
10% 
0402 
X7R 
1 2
C465 
SC1U16V2KX-7-GP 
1uF 
16V 
10% 
0402 
X6S 
1 2
C480 
SC1KP50V2KX-1GP 
1000pF 
50V 
10% 
0402 
X7R 
1 2
C431 
SCD1U16V2KX-3GP 
0.1uF 
16V 
10% 
0402 
X7R 
1 2
C475 
SC1KP50V2KX-1GP 
1000pF 
50V 
10% 
0402 
X7R 
1 2
C437 
SCD1U16V2KX-3GP 
0.1uF 
16V 
10% 
0402 
X7R 
1 2
C435 
SCD1U16V2KX-3GP 
0.1uF 
16V 
10% 
0402 
X7R 
1 2
C477 
SC1KP50V2KX-1GP 
1000pF 
50V 
10% 
0402 
X7R 
1 2
C436 
SCD1U16V2KX-3GP 
0.1uF 
16V 
10% 
0402 
X7R 
1 2
C456 
SCD1U16V2KX-3GP 
0.1uF 
16V 
10% 
0402 
X7R 
1 2
C448 
SCD1U16V2KX-3GP 
0.1uF 
16V 
10% 
0402 
X7R 
1 2
C459 
SCD1U16V2KX-3GP 
0.1uF 
16V 
10% 
0402 
X7R 
1 2
9 OF 14 U1I 
SAS3008C0-1-DB-500020657-1-GP 
VSS A11 
VSS A15 
VSS B11 
VSS B14 
VSS B15 
VSS C11 
VSS C14 
VSS C15 
VSS D5 
VSS D7 
VSS D9 
VSS D11 
VSS D12 
VSS D13 
VSS D14 
VSS D15 
VSS D17 
VSS D19 
VSS D21 
VSS D23 
VSS D25 
VSS D27 
VSS E4 
VSS E6 
VSS E8 
VSS E10 
VSS E11 
VSS E12 
VSS E13 
VSS E14 
VSS E16 
VSS E18 
VSS E20 
VSS E22 
VSS E24 
VSS E26 
VSS F5 
VSS F11 
VSS F12 
VSS F13 
VSS F14 
VSS F15 
VSS F16 
VSS F17 
VSS F18 
VSS F19 
VSS F20 
VSS F21 
VSS F22 
VSS F23 
VSS F24 
VSS F25 
VSS F27 
VSS G4 
VSS G7 
VSS G8 
VSS G9 
VSS G11 
VSS G12 
VSS G13 
VSS G14 
VSS G15 
VSS G16 
VSS G17 
VSS G18 
VSS G19 
VSS G20 
VSS G21 
VSS G22 
VSS G23 
VSS G24 
VSS G25 
VSS G26 
VSS H5 
VSS H7 
VSS H8 
VSS H10 
VSS H12 
14 OF 14 U1N 
SAS3008C0-1-DB-500020657-1-GP 
VSS AE26 
VSS AF2 
VSS AF3 
VSS AF5 
VSS AF6 
VSS AF9 
VSS AF12 
VSS AF15 
VSS AF18 
VSS AF19 
VSS AF21 
VSS AF23 
VSS AF25 
VSS AF27 
VSS AG3 
VSS AG6 
VSS AG15 
VSS AG20 
VSS AG22 
VSS AG24 
VSS AG26 
VSS AH3 
VSS AH6 
VSS AH7 
VSS AH8 
VSS AH9 
VSS AH10 
VSS AH11 
VSS AH12 
VSS AH13 
VSS AH14 
VSS AH16 
VSS AH17 
VSS AH18 
VSS AJ2 
VSS AJ4 
VSS AJ5 
VSS AJ6 
VSS AJ9 
VSS AJ12 
VSS AJ15 
VSS AJ18 
VSS AK2 
VSS AK3 
C443 
SCD1U16V2KX-3GP 
0.1uF 
16V 
10% 
0402 
X7R 
1 2
C442 
SCD1U16V2KX-3GP 
0.1uF 
16V 
10% 
0402 
X7R 
1 2
C445 
SCD1U16V2KX-3GP 
0.1uF 
16V 
10% 
0402 
X7R 
1 2
C444 
SCD1U16V2KX-3GP 
0.1uF 
16V 
10% 
0402 
X7R 
1 2
C440 
SCD1U16V2KX-3GP 
0.1uF 
16V 
10% 
0402 
X7R 
1 2
C432 
SCD1U16V2KX-3GP 
0.1uF 
16V 
10% 
0402 
X7R 
1 2
C474 
SC1KP50V2KX-1GP 
1000pF 
50V 
10% 
0402 
X7R 
1 2
C441 
SCD1U16V2KX-3GP 
0.1uF 
16V 
10% 
0402 
X7R 
1 2
C438 
SCD1U16V2KX-3GP 
0.1uF 
16V 
10% 
0402 
X7R 
1 2
C466 
SC1U16V2KX-7-GP 
1uF 
16V 
10% 
0402 
X6S 
1 2
C470 
SCD1U16V2KX-3GP 
0.1uF 
16V 
10% 
0402 
X7R 
1 2
C450 
SCD1U16V2KX-3GP 
0.1uF 
16V 
10% 
0402 
X7R 
1 2
C461 
SC1U16V2KX-7-GP 
1uF 
16V 
10% 
0402 
X6S 
1 2
C468 
SCD1U16V2KX-3GP 
0.1uF 
16V 
10% 
0402 
X7R 
1 2
C469 
SCD1U16V2KX-3GP 
0.1uF 
16V 
10% 
0402 
X7R 
1 2
C455 
SCD1U16V2KX-3GP 
0.1uF 
16V 
10% 
0402 
X7R 
1 2
C433 
SCD1U16V2KX-3GP 
0.1uF 
16V 
10% 
0402 
X7R 
1 2
C472 
SCD1U16V2KX-3GP 
0.1uF 
16V 
10% 
0402 
X7R 
1 2
C449 
SCD1U16V2KX-3GP 
0.1uF 
16V 
10% 
0402 
X7R 
1 2
C434 
SCD1U16V2KX-3GP 
0.1uF 
16V 
10% 
0402 
X7R 
1 2
C479 
SC1KP50V2KX-1GP 
1000pF 
50V 
10% 
0402 
X7R 
1 2
C454 
SCD1U16V2KX-3GP 
0.1uF 
16V 
10% 
0402 
X7R 
1 2
C478 
SC1KP50V2KX-1GP 
1000pF 
50V 
10% 
0402 
X7R 
1 2
10 OF 14 U1J 
SAS3008C0-1-DB-500020657-1-GP 
VSS H13 
VSS H14 
VSS H15 
VSS H16 
VSS H17 
VSS H18 
VSS H19 
VSS H20 
VSS H21 
VSS H22 
VSS H23 
VSS H24 
VSS H25 
VSS H27 
VSS J4 
VSS J7 
VSS J9 
VSS J11 
VSS J13 
VSS J14 
VSS J15 
VSS J16 
VSS J17 
VSS J18 
VSS J19 
VSS J20 
VSS J21 
VSS J22 
VSS J23 
VSS J24 
VSS J25 
VSS J26 
VSS K5 
VSS K7 
VSS K8 
VSS K10 
VSS K12 
VSS K14 
VSS K15 
VSS K16 
VSS K17 
VSS K18 
VSS K19 
VSS K20 
VSS K22 
VSS K23 
VSS K24 
VSS K25 
VSS K27 
VSS L4 
VSS L7 
VSS L8 
VSS L9 
VSS L11 
VSS L13 
VSS L15 
VSS L17 
VSS L19 
VSS L21 
VSS L23 
VSS L24 
VSS L25 
VSS L26 
VSS L28 
VSS M5 
VSS M7 
VSS M8 
VSS M10 
VSS M12 
VSS M14 
VSS M16 
VSS M18 
VSS M20 
VSS M22 
VSS M23 
VSS M24 
VSS M25 
VSS M26 
C457 
SCD1U16V2KX-3GP 
0.1uF 
16V 
10% 
0402 
X7R 
1 2
C463 
SC1U16V2KX-7-GP 
1uF 
16V 
10% 
0402 
X6S 
1 2
C458 
SCD1U16V2KX-3GP 
0.1uF 
16V 
10% 
0402 
X7R 
1 2
C462 
SC1U16V2KX-7-GP 
1uF 
16V 
10% 
0402 
X6S 
1 2
11 OF 14 U1K 
SAS3008C0-1-DB-500020657-1-GP 
VSS M27 
VSS M28 
VSS M29 
VSS M30 
VSS N1 
VSS N2 
VSS N4 
VSS N7 
VSS N8 
VSS N9 
VSS N10 
VSS N11 
VSS N13 
VSS N15 
VSS N17 
VSS N19 
VSS N21 
VSS N22 
VSS N23 
VSS N24 
VSS N25 
VSS N26 
VSS P3 
VSS P7 
VSS P8 
VSS P9 
VSS P10 
VSS P11 
VSS P12 
VSS P14 
VSS P16 
VSS P18 
VSS P20 
VSS P22 
VSS P23 
VSS P24 
VSS P25 
VSS P27 
VSS R1 
VSS R2 
VSS R3 
VSS R4 
VSS R8 
VSS R9 
VSS R10 
VSS R11 
VSS R13 
VSS R15 
VSS R17 
VSS R19 
VSS R21 
VSS R22 
VSS R23 
VSS R24 
VSS R25 
VSS R26 
VSS T3 
VSS T5 
VSS T7 
VSS T8 
VSS T10 
VSS T11 
VSS T12 
VSS T14 
VSS T16 
VSS T18 
VSS T20 
VSS T22 
VSS T23 
VSS T24 
VSS T25 
VSS T27 
VSS U2 
VSS U3 
VSS U4 
VSS U5 
VSS U6 
VSS U7 
C467 
SCD1U16V2KX-3GP 
0.1uF 
16V 
10% 
0402 
X7R 
1 2
12 OF 14 U1L 
SAS3008C0-1-DB-500020657-1-GP 
VSS U8 
VSS U9 
VSS U11 
VSS U13 
VSS U15 
VSS U17 
VSS U19 
VSS U21 
VSS U22 
VSS U23 
VSS U24 
VSS U25 
VSS U26 
VSS V3 
VSS V6 
VSS V8 
VSS V10 
VSS V12 
VSS V14 
VSS V16 
VSS V18 
VSS V20 
VSS V22 
VSS V23 
VSS V24 
VSS V25 
VSS V27 
VSS W3 
VSS W6 
VSS W7 
VSS W8 
VSS W9 
VSS W10 
VSS W11 
VSS W12 
VSS W13 
VSS W15 
VSS W17 
VSS W19 
VSS W21 
VSS W22 
VSS W23 
VSS W24 
VSS W25 
VSS W26 
VSS Y2 
VSS Y3 
VSS Y5 
VSS Y8 
VSS Y9 
VSS Y10 
VSS Y11 
VSS Y12 
VSS Y13 
VSS Y14 
VSS Y15 
VSS Y16 
VSS Y18 
VSS Y20 
VSS Y22 
VSS Y23 
VSS Y24 
VSS Y25 
VSS Y27 
VSS AA3 
VSS AA6 
VSS AA7 
VSS AA8 
VSS AA9 
VSS AA10 
VSS AA11 
VSS AA12 
VSS AA13 
VSS AA14 
VSS AA15 
VSS AA16 
VSS AA17 
VSS AA18 
C447 
SCD1U16V2KX-3GP 
0.1uF 
16V 
10% 
0402 
X7R 
1 2



5
5
4
4
3
3
2
2
1
1
D D
C C
B B
A A
IOC_SDA_4 
IOC_SCL_4 
I2C_IOC_SDA 
IOC_UART_0_TX_R 
IOC_UART_0_RX_R 
IOC_UART_R_TX 
IOC_UART_R_RX 
IOM_IOC_UART_TX 
IOM_IOC_UART_RX 
I2C_IOC_SCL 
IOM_IOC_UART_TX 
IOM_IOC_UART_RX 
U43_VREF2 
P3V3_STBY 
P1V8 
P1V8 
P3V3 
P3V3_STBY 
IOC_SCL_4 38 
IOC_SDA_4 38 
I2C_IOC_SCL 20 
I2C_IOC_SDA 20 
IOC_UART_0_RX 39 
IOC_UART_0_TX 39 
SYS_RST_N_0 39 
IOM_FULL_PGOOD 21,35 
Title 
Size Document Number Rev
Date: Sheet 
of 
Bryce Canyon_IO Module 2
SAS3008_I2C&UART LEVEL SHIFT 
A3 
44 47Friday, December 08, 2017 
Bryce Canyon_IO Module 
http://www.wiwynn.com 
8F, 90, Sec.1, Xintai 5th Rd., Xizhi Dist.,
New Taipei City 22102, Taiwan (R.O.C.)
Title 
Size Document Number Rev
Date: Sheet 
of 
Bryce Canyon_IO Module 2
SAS3008_I2C&UART LEVEL SHIFT 
A3 
44 47Friday, December 08, 2017 
Bryce Canyon_IO Module 
http://www.wiwynn.com 
8F, 90, Sec.1, Xintai 5th Rd., Xizhi Dist.,
New Taipei City 22102, Taiwan (R.O.C.)
Title 
Size Document Number Rev
Date: Sheet 
of 
Bryce Canyon_IO Module 2
SAS3008_I2C&UART LEVEL SHIFT 
A3 
44 47Friday, December 08, 2017 
Bryce Canyon_IO Module 
http://www.wiwynn.com 
8F, 90, Sec.1, Xintai 5th Rd., Xizhi Dist.,
New Taipei City 22102, Taiwan (R.O.C.)
R833 
200KR2F-L-GP 
200k ohm 
1/16W 
1% 
0402 
12
U43 
PCA9306DCTT-GP 
GND 1
VREF1 2
SCL1 3
SDA1 4 SDA2 5
SCL2 6
VREF2 7
EN 8
R693 0 ohm 0402 12
CN5 
PIN-CON3-5-GP 
NOPOP 
1
2
3
R692 0 ohm 0402 12
U44 
TXS0102DCUR-1-GP 
B2 1
GND 2
VCCA 3
A2 4 A1 5
OE 6
VCCB 7
B1 8
R597 0 ohm 0402 
NOPOP 
12
R689 
2K2R2F-GP 
2.2k ohm 
1/16W 
1% 
0402 
12
C481 
SCD1U16V2KX-3GP 
0.1uF 
16V 
10% 
0402 
X7R 
1 2
C483 
SCD1U16V2KX-3GP 
0.1uF 
16V 
10% 
0402 
X7R 
1 2
R694 0 ohm 0402 12
C482 
SCD1U16V2KX-3GP 
0.1uF 
16V 
10% 
0402 
X7R 
1 2
C484 
SCD1U16V2KX-3GP 
0.1uF 
16V 
10% 
0402 
X7R 
1 2
R690 
2K2R2F-GP 
2.2k ohm 
1/16W 
1% 
0402 
12
R691 0 ohm 0402 12



5
5
4
4
3
3
2
2
1
1
D D
C C
B B
A A
EXT MINI SAS HD CONN_1 & 2
1000PF 
2KV 
1206 
X7R 
1000PF 
2KV 
1206 
X7R 
ZDEF_EXTA_TP_A1 
ZDEF_EXTA_TP_A2 
ZDEF_EXTA_TP_B1 
ZDEF_EXTA_TP_B2 
PHY_IOC_TO_CON_A_0_DP 
PHY_IOC_TO_CON_A_0_DN 
ZDEF_EXTA_TP_D2 
ZDEF_EXTA_TP_D1 
ZDEF_EXTA_TP_C2 
ZDEF_EXTA_TP_C1 
PHY_CON_A_TO_IOC_0_DN_C 
PHY_CON_A_TO_IOC_0_DP_C 
ZDEF_EXTB_TP_A1 
ZDEF_EXTB_TP_A2 
ZDEF_EXTB_TP_B1 
ZDEF_EXTB_TP_B2 
PHY_IOC_TO_CON_B_0_DP 
PHY_IOC_TO_CON_B_0_DN 
ZDEF_EXTB_TP_D2 
ZDEF_EXTB_TP_D1 
ZDEF_EXTB_TP_C2 
ZDEF_EXTB_TP_C1 
PHY_CON_B_TO_IOC_0_DN_C 
PHY_CON_B_TO_IOC_0_DP_C 
PHY_CON_A_TO_IOC_1_DN_C 
PHY_CON_A_TO_IOC_1_DP_C 
PHY_CON_A_TO_IOC_2_DN_C 
PHY_CON_A_TO_IOC_2_DP_C 
PHY_CON_A_TO_IOC_3_DN_C 
PHY_CON_A_TO_IOC_3_DP_C 
PHY_CON_B_TO_IOC_1_DN_C 
PHY_CON_B_TO_IOC_1_DP_C 
PHY_CON_B_TO_IOC_2_DN_C 
PHY_CON_B_TO_IOC_2_DP_C 
PHY_CON_B_TO_IOC_3_DN_C 
PHY_CON_B_TO_IOC_3_DP_C 
PHY_IOC_TO_CON_A_1_DN 
PHY_IOC_TO_CON_A_1_DP 
PHY_IOC_TO_CON_B_1_DN 
PHY_IOC_TO_CON_B_1_DP 
PHY_IOC_TO_CON_B_2_DN 
PHY_IOC_TO_CON_B_2_DP 
PHY_IOC_TO_CON_B_3_DN 
PHY_IOC_TO_CON_B_3_DP 
PHY_IOC_TO_CON_A_3_DN 
PHY_IOC_TO_CON_A_3_DP 
PHY_IOC_TO_CON_A_2_DP 
PHY_IOC_TO_CON_A_2_DN 
EXT1_CONN_GND 
EXT2_CONN_GND 
PHY_IOC_TO_CON_A_0_DP 37 
PHY_IOC_TO_CON_A_0_DN 37 
PHY_CON_A_TO_IOC_0_DP 37 
PHY_CON_A_TO_IOC_0_DN 37 
PHY_IOC_TO_CON_B_0_DP 37 
PHY_IOC_TO_CON_B_0_DN 37 
PHY_CON_B_TO_IOC_0_DP 37 
PHY_CON_B_TO_IOC_0_DN 37 
PHY_CON_A_TO_IOC_1_DP 37 
PHY_CON_A_TO_IOC_1_DN 37 
PHY_CON_A_TO_IOC_2_DN 37 
PHY_CON_A_TO_IOC_2_DP 37 
PHY_CON_A_TO_IOC_3_DN 37 
PHY_CON_A_TO_IOC_3_DP 37 
PHY_CON_B_TO_IOC_1_DP 37 
PHY_CON_B_TO_IOC_1_DN 37 
PHY_CON_B_TO_IOC_2_DP 37 
PHY_CON_B_TO_IOC_2_DN 37 
PHY_CON_B_TO_IOC_3_DP 37 
PHY_CON_B_TO_IOC_3_DN 37 
PHY_IOC_TO_CON_A_1_DP 37 
PHY_IOC_TO_CON_A_1_DN 37 
PHY_IOC_TO_CON_B_1_DN 37 
PHY_IOC_TO_CON_B_1_DP 37 
PHY_IOC_TO_CON_B_2_DP 37 
PHY_IOC_TO_CON_B_2_DN 37 
PHY_IOC_TO_CON_B_3_DP 37 
PHY_IOC_TO_CON_B_3_DN 37 
PHY_IOC_TO_CON_A_3_DP 37 
PHY_IOC_TO_CON_A_3_DN 37 
PHY_IOC_TO_CON_A_2_DP 37 
PHY_IOC_TO_CON_A_2_DN 37 
Title 
Size Document Number Rev
Date: Sheet 
of 
Bryce Canyon_IO Module 2
SAS3008_EXT_MINI SAS CONN*2 
A3 
45 47Friday, December 08, 2017 
Bryce Canyon_IO Module 
http://www.wiwynn.com 
8F, 90, Sec.1, Xintai 5th Rd., Xizhi Dist.,
New Taipei City 22102, Taiwan (R.O.C.)
Title 
Size Document Number Rev
Date: Sheet 
of 
Bryce Canyon_IO Module 2
SAS3008_EXT_MINI SAS CONN*2 
A3 
45 47Friday, December 08, 2017 
Bryce Canyon_IO Module 
http://www.wiwynn.com 
8F, 90, Sec.1, Xintai 5th Rd., Xizhi Dist.,
New Taipei City 22102, Taiwan (R.O.C.)
Title 
Size Document Number Rev
Date: Sheet 
of 
Bryce Canyon_IO Module 2
SAS3008_EXT_MINI SAS CONN*2 
A3 
45 47Friday, December 08, 2017 
Bryce Canyon_IO Module 
http://www.wiwynn.com 
8F, 90, Sec.1, Xintai 5th Rd., Xizhi Dist.,
New Taipei City 22102, Taiwan (R.O.C.)
C486 0.01uF 16V 10% 0201 X7R 1 2
C494 0.01uF 16V 10% 0201 X7R 1 2
C491 0.01uF 16V 10% 0201 X7R 1 2
TP182 1
EXT2 
MINI-SAS-36P-7-GP 
A1 A1 
A2 A2 
A3 A3 
A4 A4 
A5 A5 
A6 A6 
A7 A7 
A8 A8 
A9 A9 
B1 B1 
B2 B2 
B3 B3 
B4 B4 
B5 B5 
B6 B6 
B7 B7 
B8 B8 
B9 B9 
G3 G3 
G4 G4 
G5 G5 
G6 G6 
G7 G7 
C1 C1 
C2 C2 
C3 C3 
C4 C4 
C5 C5 
C6 C6 
C7 C7 
C8 C8 
C9 C9 
D1 D1 
D2 D2 
D3 D3 
D4 D4 
D5 D5 
D6 D6 
D7 D7 
D8 D8 
D9 D9 
G1 G1 
G2 G2 
TP176 1
C493 0.01uF 16V 10% 0201 X7R 1 2
C487 0.01uF 16V 10% 0201 X7R 1 2
TP180 1
C498 0.01uF 16V 10% 0201 X7R 1 2
C500 0.01uF 16V 10% 0201 X7R 1 2
TP184 1
TP177 1
C527 
SC1000P2KV6KX-GP-U 
1 2
TP171 1
C495 0.01uF 16V 10% 0201 X7R 1 2
TP185 1
C497 0.01uF 16V 10% 0201 X7R 1 2
R44 
1MR2F-GP 
1M ohm 
1/16W 
1% 
0402 
1 2
TP170 1
TP183 1
TP172 1
C526 
SC1000P2KV6KX-GP-U 
1 2
C499 0.01uF 16V 10% 0201 X7R 1 2
C496 0.01uF 16V 10% 0201 X7R 1 2
EXT1 
MINI-SAS-36P-7-GP 
A1 A1 
A2 A2 
A3 A3 
A4 A4 
A5 A5 
A6 A6 
A7 A7 
A8 A8 
A9 A9 
B1 B1 
B2 B2 
B3 B3 
B4 B4 
B5 B5 
B6 B6 
B7 B7 
B8 B8 
B9 B9 
G3 G3 
G4 G4 
G5 G5 
G6 G6 
G7 G7 
C1 C1 
C2 C2 
C3 C3 
C4 C4 
C5 C5 
C6 C6 
C7 C7 
C8 C8 
C9 C9 
D1 D1 
D2 D2 
D3 D3 
D4 D4 
D5 D5 
D6 D6 
D7 D7 
D8 D8 
D9 D9 
G1 G1 
G2 G2 
TP179 1
R39 
1MR2F-GP 
1M ohm 
1/16W 
1% 
0402 
1 2
TP174 1
TP173 1
TP178 1
C490 0.01uF 16V 10% 0201 X7R 1 2
C492 0.01uF 16V 10% 0201 X7R 1 2
TP175 1
C488 0.01uF 16V 10% 0201 X7R 1 2
TP181 1
C501 0.01uF 16V 10% 0201 X7R 1 2
C489 0.01uF 16V 10% 0201 X7R 1 2



5
5
4
4
3
3
2
2
1
1
D D
C C
B B
A A
EXT1_LED_BLUE_D EXT1_LED_BLUE 
EXT1_LED_BLUE_G_Q24 
IOC_EXT1_LED_Y_XOR 
EXT1_LED_YELLOW_D 
EXT1_LED_YELLOW_G1 
EXT2_LED_BLUE_D EXT2_LED_BLUE 
EXT2_LED_BLUE_G_Q27 
EXT2_LED_BLUE_G2 
IOC_EXT2_LED_Y_XOR 
EXT2_LED_YELLOW_D 
EXT2_LED_YELLOW_G1 
EXT1_LED_BLUE_G2 
EXT1_LED_BLUE EXT1_LED_YELLOW_D1 EXT1_LED_YELLOW 
EXT2_LED_BLUE EXT2_LED_YELLOW_D1 EXT2_LED_YELLOW 
P1V8 
P5V_STBY 
P1V8 
P3V3_STBY P3V3_STBY P3V3_STBY 
P1V8 
P5V_STBY 
P1V8 
P5V_STBY 
P3V3_STBY P3V3_STBY P3V3_STBY 
P5V_STBY IOC_EXT1_LED_B 38,46 
IOC_EXT1_LED_Y 38 
BMC_EXT1_LED_Y 21,46 
BMC_EXT1_LED_Y 21,46 
IOC_EXT1_LED_B 38,46 
IOC_EXT2_LED_B 38,46 
IOC_EXT2_LED_Y 38 
BMC_EXT2_LED_Y 21,46 
BMC_EXT2_LED_Y 21,46 
IOC_EXT2_LED_B 38,46 
Title 
Size Document Number Rev
Date: Sheet 
of 
Bryce Canyon_IO Module 2
SAS3008_SAS CONN LED 
A3 
46 47Friday, December 08, 2017 
Bryce Canyon_IO Module 
http://www.wiwynn.com 
8F, 90, Sec.1, Xintai 5th Rd., Xizhi Dist.,
New Taipei City 22102, Taiwan (R.O.C.)
Title 
Size Document Number Rev
Date: Sheet 
of 
Bryce Canyon_IO Module 2
SAS3008_SAS CONN LED 
A3 
46 47Friday, December 08, 2017 
Bryce Canyon_IO Module 
http://www.wiwynn.com 
8F, 90, Sec.1, Xintai 5th Rd., Xizhi Dist.,
New Taipei City 22102, Taiwan (R.O.C.)
Title 
Size Document Number Rev
Date: Sheet 
of 
Bryce Canyon_IO Module 2
SAS3008_SAS CONN LED 
A3 
46 47Friday, December 08, 2017 
Bryce Canyon_IO Module 
http://www.wiwynn.com 
8F, 90, Sec.1, Xintai 5th Rd., Xizhi Dist.,
New Taipei City 22102, Taiwan (R.O.C.)
Q1 
Q2 
D1 
G2 
S2 
G1 
S1 
D2 
Q206 
SSM6P39TU-GP 
1
2
3 4
5
6
U51 
SN74LVC1G08DCKR-GP 
B2
A1
GND 3 Y 4
VCC 5
C517 
SCD1U16V2KX-3GP 
0.1uF 
16V 
10% 
0402 
X7R 
1 2
C515 
SCD1U16V2KX-3GP 
0.1uF 
16V 
10% 
0402 
X7R 
1 2
Q27 
SSM3K324R-GP 
S
G
D
R801 130R3F-GP 
130 ohm 1/10W 1% 0603 
1 2
C523 
SCD1U16V2KX-3GP 
0.1uF 
16V 
10% 
0402 
X7R 
1 2
R735 
1KR2F-3-GP 
1k ohm 
1/16W 
1% 
0402 
1 2
C516 
SCD1U16V2KX-3GP 
0.1uF 
16V 
10% 
0402 
X7R 
1 2
U50 
74LVC1G86DCKR-GP 
A1
B2
GND 3 Y 4
VCC 5
R695 
1KR2F-3-GP 
1k ohm 
1/16W 
1% 
0402 
1 2
C521 
SCD1U16V2KX-3GP 
0.1uF 
16V 
10% 
0402 
X7R 
1 2
BLUE YELLOW 
LED3 
LED-BY-14-GP 
1
2
3R737 120R3F-L-GP 
120 ohm 1/10W 1% 0603 
1 2
R696 
1KR2F-3-GP 
1k ohm 
1/16W 
1% 
0402 
1 2
U48 
SN74LVC1G08DCKR-GP 
B2
A1
GND 3 Y 4
VCC 5
C514 
SCD1U16V2KX-3GP 
0.1uF 
16V 
10% 
0402 
X7R 
1 2
Q24 
SSM3K324R-GP 
S
G
D
BLUE YELLOW 
LED2 
LED-BY-14-GP 
1
2
3
U47 
74LVC1G86DCKR-GP 
A1
B2
GND 3 Y 4
VCC 5
U49 
SN74LVC1G08DCKR-GP 
B2
A1
GND 3 Y 4
VCC 5
Q1 
Q2 
D1 
G2 
S2 
G1 
S1 
D2 
Q205 
SSM6P39TU-GP 
1
2
3 4
5
6
R733 120R3F-L-GP 
120 ohm 1/10W 1% 0603 
1 2
U52 
SN74LVC1G08DCKR-GP 
B2
A1
GND 3 Y 4
VCC 5
Q21 
SSM3K324R-GP 
S
G
D
R800 130R3F-GP 
130 ohm 1/10W 1% 0603 
1 2
Q22 
SSM3K324R-GP 
S
G
D
R730 
1KR2F-3-GP 
1k ohm 
1/16W 
1% 
0402 
1 2



5
5
4
4
3
3
2
2
1
1
D D
C C
B B
A A
Title 
Size Document Number Rev
Date: Sheet 
of 
Bryce Canyon_IO Module 2
SCREW HOLE 
A3 
47 47Friday, December 08, 2017 
Bryce Canyon_IO Module 
http://www.wiwynn.com 
8F, 90, Sec.1, Xintai 5th Rd., Xizhi Dist.,
New Taipei City 22102, Taiwan (R.O.C.)
Title 
Size Document Number Rev
Date: Sheet 
of 
Bryce Canyon_IO Module 2
SCREW HOLE 
A3 
47 47Friday, December 08, 2017 
Bryce Canyon_IO Module 
http://www.wiwynn.com 
8F, 90, Sec.1, Xintai 5th Rd., Xizhi Dist.,
New Taipei City 22102, Taiwan (R.O.C.)
Title 
Size Document Number Rev
Date: Sheet 
of 
Bryce Canyon_IO Module 2
SCREW HOLE 
A3 
47 47Friday, December 08, 2017 
Bryce Canyon_IO Module 
http://www.wiwynn.com 
8F, 90, Sec.1, Xintai 5th Rd., Xizhi Dist.,
New Taipei City 22102, Taiwan (R.O.C.)
NUT1 
STF256R168H278-GP 
1